FILE_TYPE = MACRO_DRAWING;
SET COLOR_WIRE YELLOW;
SET COLOR_PROP ORANGE;
SET COLOR_DOT WHITE;
SET COLOR_ARC YELLOW;
SET COLOR_BODY GREEN;
SET COLOR_NOTE PURPLE;
SET PROP_DISPLAY VALUE;
SET PAGE_NUMBER P254;
FORCEADD UNIVERSAL_GND..1
(2600 775);
FORCEPROP 3 LASTPIN (2600 825) SIG_NAME GND\g
J 0
(2610 835);
DISPLAY 0.659574 (2610 835);
PAINT MONO (2610 835);
DISPLAY INVISIBLE (2610 835);
FORCEPROP 2 LAST CDS_LIB logical_power
J 0
(2600 775);
PAINT MONO (2600 775);
DISPLAY INVISIBLE (2600 775);
FORCEPROP 1 LAST HDL_POWER GND
J 1
(2625 700);
DISPLAY 0.872340 (2625 700);
PAINT GREEN (2625 700);
DISPLAY INVISIBLE (2625 700);
FORCEPROP 1 LAST PATH I1
J 0
(2675 775);
DISPLAY 0.872340 (2675 775);
PAINT AQUA (2675 775);
DISPLAY INVISIBLE (2675 775);
FORCEADD UNIVERSAL_GND..1
(3000 1750);
FORCEPROP 3 LASTPIN (3000 1800) SIG_NAME GND\g
J 0
(3010 1810);
DISPLAY 0.659574 (3010 1810);
PAINT MONO (3010 1810);
DISPLAY INVISIBLE (3010 1810);
FORCEPROP 2 LAST CDS_LIB logical_power
J 0
(3000 1750);
PAINT MONO (3000 1750);
DISPLAY INVISIBLE (3000 1750);
FORCEPROP 1 LAST HDL_POWER GND
J 1
(3025 1675);
DISPLAY 0.872340 (3025 1675);
PAINT GREEN (3025 1675);
DISPLAY INVISIBLE (3025 1675);
FORCEPROP 1 LAST PATH I10
J 0
(3075 1750);
DISPLAY 0.872340 (3075 1750);
PAINT AQUA (3075 1750);
DISPLAY INVISIBLE (3075 1750);
FORCEADD Q_CAP..1
(3000 2000);
FORCEPROP 1 LAST PART_NUMBER CH5222KEB01
J 0
(3050 1825);
DISPLAY 0.617021 (3050 1825);
PAINT BLUE (3050 1825);
DISPLAY INVISIBLE (3050 1825);
FORCEPROP 1 LAST MATERIAL X6S
J 0
(3050 1925);
DISPLAY 0.617021 (3050 1925);
PAINT SKYBLUE (3050 1925);
FORCEPROP 1 LAST TOLERANCE 10%
J 0
(3050 1975);
DISPLAY 0.617021 (3050 1975);
PAINT SKYBLUE (3050 1975);
FORCEPROP 1 LAST VALUE 2.2UF
J 0
(3050 2075);
DISPLAY 0.617021 (3050 2075);
PAINT SKYBLUE (3050 2075);
FORCEPROP 1 LAST VOLTAGE 10V
J 0
(3050 2025);
DISPLAY 0.617021 (3050 2025);
PAINT SKYBLUE (3050 2025);
FORCEPROP 1 LAST PACK_TYPE C0402
J 0
(3050 1875);
DISPLAY 0.617021 (3050 1875);
PAINT SKYBLUE (3050 1875);
FORCEPROP 1 LAST LOCATION PC270
J 0
(3050 2125);
DISPLAY 0.617021 (3050 2125);
PAINT AQUA (3050 2125);
FORCEPROP 1 LASTPIN (3000 2100) $PN 1
J 0
(3010 2080);
DISPLAY 0.617021 (3010 2080);
PAINT MONO (3010 2080);
FORCEPROP 1 LASTPIN (3000 1900) $PN 2
J 0
(3010 1880);
DISPLAY 0.617021 (3010 1880);
PAINT MONO (3010 1880);
FORCEPROP 2 LAST CDS_LIB pure_quanta
J 0
(3000 2000);
DISPLAY INVISIBLE (3000 2000);
FORCEPROP 1 LAST PATH I11
J 0
(3050 2150);
DISPLAY 0.978723 (3050 2150);
PAINT WHITE (3050 2150);
DISPLAY INVISIBLE (3050 2150);
FORCEPROP 1 LAST LOCATION PC270
J 0
(3050 2175);
DISPLAY 1.021277 (3050 2175);
PAINT AQUA (3050 2175);
DISPLAY INVISIBLE (3050 2175);
FORCEPROP 0 LAST $SEC 1
J 0
(3050 2175);
DISPLAY 0.680851 (3050 2175);
PAINT MONO (3050 2175);
DISPLAY INVISIBLE (3050 2175);
FORCEPROP 0 LAST CDS_SEC 1
J 0
(3050 2175);
DISPLAY 1.021277 (3050 2175);
DISPLAY INVISIBLE (3050 2175);
FORCEADD Q_CAP..2
(3325 1300);
FORCEPROP 1 LAST PART_NUMBER CH4104K1B00
J 1
(3600 1350);
DISPLAY 0.617021 (3600 1350);
PAINT BLUE (3600 1350);
DISPLAY INVISIBLE (3600 1350);
FORCEPROP 1 LAST PACK_TYPE 0402
J 1
(3825 1300);
DISPLAY 0.617021 (3825 1300);
PAINT SKYBLUE (3825 1300);
FORCEPROP 1 LAST TOLERANCE 10%
J 2
(3975 1350);
DISPLAY 0.617021 (3975 1350);
PAINT SKYBLUE (3975 1350);
FORCEPROP 1 LAST MATERIAL X7R
J 0
(3775 1350);
DISPLAY 0.617021 (3775 1350);
PAINT SKYBLUE (3775 1350);
FORCEPROP 1 LAST VALUE 0.1UF
J 2
(3625 1300);
DISPLAY 0.617021 (3625 1300);
PAINT SKYBLUE (3625 1300);
FORCEPROP 1 LAST VOLTAGE 25V
J 0
(3650 1300);
DISPLAY 0.617021 (3650 1300);
PAINT SKYBLUE (3650 1300);
FORCEPROP 1 LAST LOCATION PC1340
J 1
(3125 1300);
DISPLAY 0.617021 (3125 1300);
PAINT AQUA (3125 1300);
FORCEPROP 1 LASTPIN (3225 1300) $PN 1
J 0
(3215 1315);
DISPLAY 0.617021 (3215 1315);
FORCEPROP 1 LASTPIN (3425 1300) $PN 2
J 0
(3410 1315);
DISPLAY 0.617021 (3410 1315);
FORCEPROP 2 LAST CDS_LIB pure_quanta
J 0
(3325 1300);
PAINT MONO (3325 1300);
DISPLAY INVISIBLE (3325 1300);
FORCEPROP 1 LAST PATH I12
J 0
(3325 1500);
DISPLAY 0.978723 (3325 1500);
PAINT WHITE (3325 1500);
DISPLAY INVISIBLE (3325 1500);
FORCEPROP 2 LAST $SEC 1
J 0
(3325 1550);
DISPLAY 0.680851 (3325 1550);
PAINT MONO (3325 1550);
DISPLAY INVISIBLE (3325 1550);
FORCEPROP 2 LAST CDS_SEC 1
J 0
(3325 1550);
DISPLAY 1.021277 (3325 1550);
DISPLAY INVISIBLE (3325 1550);
FORCEADD ISL99390FRZTR5935..1
(4525 1500);
FORCEPROP 1 LAST PART_NUMBER AL099390004
J 0
(4225 2300);
DISPLAY 0.617021 (4225 2300);
PAINT BLUE (4225 2300);
DISPLAY INVISIBLE (4225 2300);
FORCEPROP 2 LAST PART_TYPE SMLF
J 0
(4225 2525);
DISPLAY 0.638298 (4225 2525);
FORCEPROP 1 LAST MATERIAL IC
J 0
(4225 2225);
DISPLAY 0.617021 (4225 2225);
PAINT SKYBLUE (4225 2225);
FORCEPROP 2 LAST VALUE ISL99390FRZ-TR5935
J 0
(4225 2475);
DISPLAY 0.617021 (4225 2475);
PAINT SKYBLUE (4225 2475);
FORCEPROP 1 LAST LOCATION PU10_P0_4
J 0
(4225 2375);
DISPLAY 0.617021 (4225 2375);
PAINT AQUA (4225 2375);
FORCEPROP 2 LASTPIN (4925 1050) $PN 2
J 0
(4935 1060);
DISPLAY 0.617021 (4935 1060);
PAINT MONO (4935 1060);
FORCEPROP 2 LASTPIN (4925 1850) $PN 33
J 0
(4935 1860);
DISPLAY 0.617021 (4935 1860);
PAINT MONO (4935 1860);
FORCEPROP 2 LASTPIN (4075 1250) $PN 31
J 2
(4065 1260);
DISPLAY 0.617021 (4065 1260);
PAINT MONO (4065 1260);
FORCEPROP 2 LASTPIN (4075 1650) $PN 35
J 2
(4065 1660);
DISPLAY 0.617021 (4065 1660);
PAINT MONO (4065 1660);
FORCEPROP 2 LASTPIN (4925 1200) $PN 6
J 0
(4935 1210);
DISPLAY 0.617021 (4935 1210);
PAINT MONO (4935 1210);
FORCEPROP 2 LASTPIN (4925 1150) $PN 41
J 0
(4935 1160);
DISPLAY 0.617021 (4935 1160);
PAINT MONO (4935 1160);
FORCEPROP 2 LASTPIN (4075 1500) $PN 38
J 2
(4065 1510);
DISPLAY 0.617021 (4065 1510);
PAINT MONO (4065 1510);
FORCEPROP 2 LASTPIN (4075 1200) $PN 37
J 2
(4065 1210);
DISPLAY 0.617021 (4065 1210);
PAINT MONO (4065 1210);
FORCEPROP 2 LASTPIN (4925 1000) $PN 5
J 0
(4935 1010);
DISPLAY 0.617021 (4935 1010);
PAINT MONO (4935 1010);
FORCEPROP 2 LASTPIN (4925 950) $PN 7_9-20_24
J 0
(4935 960);
DISPLAY 0.617021 (4935 960);
PAINT MONO (4935 960);
FORCEPROP 2 LASTPIN (4925 900) $PN 40
J 0
(4935 910);
DISPLAY 0.617021 (4935 910);
PAINT MONO (4935 910);
FORCEPROP 2 LASTPIN (4925 1600) $PN 32
J 0
(4935 1610);
DISPLAY 0.617021 (4935 1610);
PAINT MONO (4935 1610);
FORCEPROP 2 LASTPIN (4075 2150) $PN 4
J 2
(4065 2160);
DISPLAY 0.617021 (4065 2160);
PAINT MONO (4065 2160);
FORCEPROP 2 LASTPIN (4075 900) $PN 34
J 2
(4065 910);
DISPLAY 0.617021 (4065 910);
PAINT MONO (4065 910);
FORCEPROP 2 LASTPIN (4075 1400) $PN 39
J 2
(4065 1410);
DISPLAY 0.617021 (4065 1410);
PAINT MONO (4065 1410);
FORCEPROP 2 LASTPIN (4925 1500) $PN 10_19
J 0
(4935 1510);
DISPLAY 0.617021 (4935 1510);
PAINT MONO (4935 1510);
FORCEPROP 2 LASTPIN (4075 1000) $PN 36
J 2
(4065 1010);
DISPLAY 0.617021 (4065 1010);
PAINT MONO (4065 1010);
FORCEPROP 2 LASTPIN (4075 1850) $PN 3
J 2
(4065 1860);
DISPLAY 0.617021 (4065 1860);
PAINT MONO (4065 1860);
FORCEPROP 2 LASTPIN (4925 2150) $PN 25_29
J 0
(4935 2160);
DISPLAY 0.617021 (4935 2160);
PAINT MONO (4935 2160);
FORCEPROP 2 LASTPIN (4925 2100) $PN 30
J 0
(4935 2110);
DISPLAY 0.617021 (4935 2110);
PAINT MONO (4935 2110);
FORCEPROP 2 LASTPIN (4925 1250) $PN 1
J 0
(4935 1260);
DISPLAY 0.617021 (4935 1260);
PAINT MONO (4935 1260);
FORCEPROP 2 LAST CDS_LIB pure_quanta
J 0
(4525 1500);
DISPLAY INVISIBLE (4525 1500);
FORCEPROP 1 LAST CDS_LMAN_SYM_OUTLINE -300,700,250,-650
J 0
(4525 1500);
DISPLAY 0.468085 (4525 1500);
PAINT GREEN (4525 1500);
DISPLAY INVISIBLE (4525 1500);
FORCEPROP 1 LAST NEEDS_NO_SIZE TRUE
J 0
(4525 1500);
DISPLAY 0.723404 (4525 1500);
PAINT GREEN (4525 1500);
DISPLAY INVISIBLE (4525 1500);
FORCEPROP 1 LAST PATH I13
J 0
(4525 1500);
DISPLAY 0.723404 (4525 1500);
PAINT GREEN (4525 1500);
DISPLAY INVISIBLE (4525 1500);
FORCEPROP 2 LAST $SEC 1
J 0
(4225 2425);
DISPLAY 0.680851 (4225 2425);
PAINT MONO (4225 2425);
DISPLAY INVISIBLE (4225 2425);
FORCEPROP 2 LAST CDS_SEC 1
J 0
(4225 2425);
DISPLAY 1.021277 (4225 2425);
DISPLAY INVISIBLE (4225 2425);
FORCEADD Q_RES..2
(3000 2500);
FORCEPROP 1 LAST PART_NUMBER CS-2202FB01
J 0
(3040 2375);
DISPLAY 0.617021 (3040 2375);
PAINT BLUE (3040 2375);
DISPLAY INVISIBLE (3040 2375);
FORCEPROP 1 LAST WATTAGE 1/16W
J 0
(3040 2475);
DISPLAY 0.617021 (3040 2475);
PAINT SKYBLUE (3040 2475);
FORCEPROP 1 LAST MATERIAL CHIP
J 0
(3040 2425);
DISPLAY 0.617021 (3040 2425);
PAINT SKYBLUE (3040 2425);
FORCEPROP 1 LAST TOLERANCE 1%
J 0
(3045 2525);
DISPLAY 0.617021 (3045 2525);
PAINT SKYBLUE (3045 2525);
FORCEPROP 1 LAST VALUE 2.2
J 0
(3045 2575);
DISPLAY 0.617021 (3045 2575);
PAINT SKYBLUE (3045 2575);
FORCEPROP 1 LAST PACK_TYPE 0402LF
J 0
(3040 2325);
DISPLAY 0.617021 (3040 2325);
PAINT SKYBLUE (3040 2325);
FORCEPROP 1 LAST LOCATION PR146
J 0
(3045 2625);
DISPLAY 0.617021 (3045 2625);
PAINT AQUA (3045 2625);
FORCEPROP 1 LASTPIN (3000 2600) $PN 1
J 0
(3005 2562);
DISPLAY 0.617021 (3005 2562);
PAINT MONO (3005 2562);
FORCEPROP 1 LASTPIN (3000 2400) $PN 2
J 0
(3005 2410);
DISPLAY 0.617021 (3005 2410);
PAINT MONO (3005 2410);
FORCEPROP 2 LAST CDS_LIB pure_quanta
J 0
(3000 2500);
DISPLAY INVISIBLE (3000 2500);
FORCEPROP 1 LAST PATH I14
J 0
(3050 2675);
DISPLAY 0.978723 (3050 2675);
PAINT WHITE (3050 2675);
DISPLAY INVISIBLE (3050 2675);
FORCEPROP 0 LAST $SEC 1
J 0
(3050 2675);
DISPLAY 0.680851 (3050 2675);
PAINT MONO (3050 2675);
DISPLAY INVISIBLE (3050 2675);
FORCEPROP 0 LAST CDS_SEC 1
J 0
(3050 2675);
DISPLAY 1.021277 (3050 2675);
DISPLAY INVISIBLE (3050 2675);
FORCEADD VCC15..1
(3000 2825);
FORCEPROP 3 LASTPIN (3000 2775) SIG_NAME PVCCIN_CPU0_PVCC\g
J 0
(3010 2785);
DISPLAY 0.659574 (3010 2785);
PAINT MONO (3010 2785);
DISPLAY INVISIBLE (3010 2785);
FORCEPROP 1 LAST HDL_POWER PVCCIN_CPU0_PVCC
J 1
(3000 2875);
DISPLAY 0.617021 (3000 2875);
PAINT GREEN (3000 2875);
FORCEPROP 2 LAST CDS_LIB logical_power
J 0
(3000 2825);
DISPLAY INVISIBLE (3000 2825);
FORCEPROP 1 LAST PATH I15
J 0
(3050 2850);
DISPLAY 0.872340 (3050 2850);
PAINT AQUA (3050 2850);
DISPLAY INVISIBLE (3050 2850);
FORCEADD UNIVERSAL_GND..1
(3425 2275);
FORCEPROP 3 LASTPIN (3425 2325) SIG_NAME GND\g
J 0
(3435 2335);
DISPLAY 0.659574 (3435 2335);
PAINT MONO (3435 2335);
DISPLAY INVISIBLE (3435 2335);
FORCEPROP 2 LAST CDS_LIB logical_power
J 0
(3425 2275);
PAINT MONO (3425 2275);
DISPLAY INVISIBLE (3425 2275);
FORCEPROP 1 LAST HDL_POWER GND
J 1
(3450 2200);
DISPLAY 0.872340 (3450 2200);
PAINT GREEN (3450 2200);
DISPLAY INVISIBLE (3450 2200);
FORCEPROP 1 LAST PATH I16
J 0
(3500 2275);
DISPLAY 0.872340 (3500 2275);
PAINT AQUA (3500 2275);
DISPLAY INVISIBLE (3500 2275);
FORCEADD Q_CAP..1
(3425 2500);
FORCEPROP 1 LAST PART_NUMBER CH5222KEB01
J 0
(3475 2375);
DISPLAY 0.617021 (3475 2375);
PAINT BLUE (3475 2375);
DISPLAY INVISIBLE (3475 2375);
FORCEPROP 1 LAST MATERIAL X6S
J 0
(3475 2425);
DISPLAY 0.617021 (3475 2425);
PAINT SKYBLUE (3475 2425);
FORCEPROP 1 LAST VALUE 2.2UF
J 0
(3475 2575);
DISPLAY 0.617021 (3475 2575);
PAINT SKYBLUE (3475 2575);
FORCEPROP 1 LAST VOLTAGE 10V
J 0
(3475 2525);
DISPLAY 0.617021 (3475 2525);
PAINT SKYBLUE (3475 2525);
FORCEPROP 1 LAST PACK_TYPE C0402
J 0
(3475 2325);
DISPLAY 0.617021 (3475 2325);
PAINT SKYBLUE (3475 2325);
FORCEPROP 1 LAST TOLERANCE 10%
J 0
(3475 2475);
DISPLAY 0.617021 (3475 2475);
PAINT SKYBLUE (3475 2475);
FORCEPROP 1 LAST LOCATION PC272_P0_4
J 0
(3475 2625);
DISPLAY 0.617021 (3475 2625);
PAINT AQUA (3475 2625);
FORCEPROP 1 LASTPIN (3425 2600) $PN 1
J 0
(3435 2580);
DISPLAY 0.617021 (3435 2580);
PAINT MONO (3435 2580);
FORCEPROP 1 LASTPIN (3425 2400) $PN 2
J 0
(3435 2380);
DISPLAY 0.617021 (3435 2380);
PAINT MONO (3435 2380);
FORCEPROP 2 LAST CDS_LIB pure_quanta
J 0
(3425 2500);
DISPLAY INVISIBLE (3425 2500);
FORCEPROP 1 LAST PATH I17
J 0
(3475 2650);
DISPLAY 0.978723 (3475 2650);
PAINT WHITE (3475 2650);
DISPLAY INVISIBLE (3475 2650);
FORCEPROP 1 LAST LOCATION PC272_P0_4
J 0
(3475 2675);
DISPLAY 1.021277 (3475 2675);
PAINT AQUA (3475 2675);
DISPLAY INVISIBLE (3475 2675);
FORCEPROP 0 LAST $SEC 1
J 0
(3475 2675);
DISPLAY 0.680851 (3475 2675);
PAINT MONO (3475 2675);
DISPLAY INVISIBLE (3475 2675);
FORCEPROP 0 LAST CDS_SEC 1
J 0
(3475 2675);
DISPLAY 1.021277 (3475 2675);
DISPLAY INVISIBLE (3475 2675);
FORCEADD OFFPAGE..1
(3100 3725);
FORCEPROP 2 LAST $XR0 266 
J 0
(2674 3725);
DISPLAY 0.638298 (2674 3725);
PAINT MONO (2674 3725);
FORCEPROP 2 LAST CDS_LIB standard
J 0
(3100 3725);
DISPLAY INVISIBLE (3100 3725);
FORCEPROP 1 LAST OFFPAGE TRUE
J 0
(3425 3600);
DISPLAY 0.872340 (3425 3600);
PAINT GREEN (3425 3600);
DISPLAY INVISIBLE (3425 3600);
FORCEPROP 1 LAST COMMENT_BODY TRUE
J 0
(3225 3625);
DISPLAY 0.872340 (3225 3625);
PAINT GREEN (3225 3625);
DISPLAY INVISIBLE (3225 3625);
FORCEPROP 2 LAST PATH I18
J 0
(2675 3775);
DISPLAY 1.021277 (2675 3775);
DISPLAY INVISIBLE (2675 3775);
FORCEADD OFFPAGE..5
(3100 3825);
FORCEPROP 2 LAST $XR4 266 
J 0
(2845 3897);
DISPLAY 0.638298 (2845 3897);
PAINT MONO (2845 3897);
FORCEPROP 2 LAST $XR3 270 
J 0
(2845 3753);
DISPLAY 0.638298 (2845 3753);
PAINT MONO (2845 3753);
FORCEPROP 2 LAST $XR2 269 
J 0
(2845 3861);
DISPLAY 0.638298 (2845 3861);
PAINT MONO (2845 3861);
FORCEPROP 2 LAST $XR1 268 
J 0
(2845 3789);
DISPLAY 0.638298 (2845 3789);
PAINT MONO (2845 3789);
FORCEPROP 2 LAST $XR0 267 
J 0
(2845 3825);
DISPLAY 0.638298 (2845 3825);
PAINT MONO (2845 3825);
FORCEPROP 2 LAST CDS_LIB standard
J 0
(3100 3825);
DISPLAY INVISIBLE (3100 3825);
FORCEPROP 1 LAST OFFPAGE TRUE
J 0
(3425 3700);
DISPLAY 0.872340 (3425 3700);
PAINT GREEN (3425 3700);
DISPLAY INVISIBLE (3425 3700);
FORCEPROP 1 LAST COMMENT_BODY TRUE
J 0
(3200 3750);
DISPLAY 0.872340 (3200 3750);
PAINT GREEN (3200 3750);
DISPLAY INVISIBLE (3200 3750);
FORCEPROP 2 LAST PATH I19
J 0
(2850 3950);
DISPLAY 1.021277 (2850 3950);
DISPLAY INVISIBLE (2850 3950);
FORCEADD Q_RES..2
R 2
(2600 1000);
FORCEPROP 1 LAST PART_NUMBER CS28872FB01
J 2
(2560 875);
DISPLAY 0.617021 (2560 875);
PAINT BLUE (2560 875);
DISPLAY INVISIBLE (2560 875);
FORCEPROP 1 LAST PACK_TYPE 0402LF
J 2
(2560 825);
DISPLAY 0.617021 (2560 825);
PAINT SKYBLUE (2560 825);
FORCEPROP 1 LAST WATTAGE 1/16W
J 2
(2560 975);
DISPLAY 0.617021 (2560 975);
PAINT SKYBLUE (2560 975);
FORCEPROP 1 LAST MATERIAL EMPTY
J 2
(2560 925);
DISPLAY 0.617021 (2560 925);
PAINT RED (2560 925);
FORCEPROP 1 LAST TOLERANCE 1%
J 2
(2555 1025);
DISPLAY 0.617021 (2555 1025);
PAINT SKYBLUE (2555 1025);
FORCEPROP 1 LAST VALUE 8.87K
J 2
(2555 1075);
DISPLAY 0.617021 (2555 1075);
PAINT SKYBLUE (2555 1075);
FORCEPROP 1 LAST LOCATION PR144
J 2
(2555 1125);
DISPLAY 0.617021 (2555 1125);
PAINT AQUA (2555 1125);
FORCEPROP 1 LASTPIN (2600 1100) $PN 1
J 2
(2595 1062);
DISPLAY 0.617021 (2595 1062);
PAINT MONO (2595 1062);
FORCEPROP 1 LASTPIN (2600 900) $PN 2
J 2
(2595 910);
DISPLAY 0.617021 (2595 910);
PAINT MONO (2595 910);
FORCEPROP 2 LAST CDS_LIB pure_quanta
J 2
(2600 1000);
DISPLAY INVISIBLE (2600 1000);
FORCEPROP 1 LAST PATH I2
J 2
(2550 1175);
DISPLAY 0.978723 (2550 1175);
PAINT WHITE (2550 1175);
DISPLAY INVISIBLE (2550 1175);
FORCEPROP 0 LAST $SEC 1
J 0
(2575 1175);
DISPLAY 0.680851 (2575 1175);
PAINT MONO (2575 1175);
DISPLAY INVISIBLE (2575 1175);
FORCEPROP 0 LAST CDS_SEC 1
J 0
(2575 1175);
DISPLAY 1.021277 (2575 1175);
DISPLAY INVISIBLE (2575 1175);
FORCEADD ISL99390FRZTR5935..1
(4550 4325);
FORCEPROP 1 LAST PART_NUMBER AL099390004
J 0
(4250 5125);
DISPLAY 0.617021 (4250 5125);
PAINT BLUE (4250 5125);
DISPLAY INVISIBLE (4250 5125);
FORCEPROP 2 LAST PART_TYPE SMLF
J 0
(4250 5350);
DISPLAY 0.638298 (4250 5350);
FORCEPROP 1 LAST MATERIAL IC
J 0
(4250 5050);
DISPLAY 0.617021 (4250 5050);
PAINT SKYBLUE (4250 5050);
FORCEPROP 2 LAST VALUE ISL99390FRZ-TR5935
J 0
(4250 5300);
DISPLAY 0.617021 (4250 5300);
PAINT SKYBLUE (4250 5300);
FORCEPROP 1 LAST LOCATION PU11_P0_3
J 0
(4250 5200);
DISPLAY 0.617021 (4250 5200);
PAINT AQUA (4250 5200);
FORCEPROP 2 LASTPIN (4950 3875) $PN 2
J 0
(4960 3885);
DISPLAY 0.617021 (4960 3885);
PAINT MONO (4960 3885);
FORCEPROP 2 LASTPIN (4950 4675) $PN 33
J 0
(4960 4685);
DISPLAY 0.617021 (4960 4685);
PAINT MONO (4960 4685);
FORCEPROP 2 LASTPIN (4100 4075) $PN 31
J 2
(4090 4085);
DISPLAY 0.617021 (4090 4085);
PAINT MONO (4090 4085);
FORCEPROP 2 LASTPIN (4100 4475) $PN 35
J 2
(4090 4485);
DISPLAY 0.617021 (4090 4485);
PAINT MONO (4090 4485);
FORCEPROP 2 LASTPIN (4950 4025) $PN 6
J 0
(4960 4035);
DISPLAY 0.617021 (4960 4035);
PAINT MONO (4960 4035);
FORCEPROP 2 LASTPIN (4950 3975) $PN 41
J 0
(4960 3985);
DISPLAY 0.617021 (4960 3985);
PAINT MONO (4960 3985);
FORCEPROP 2 LASTPIN (4100 4325) $PN 38
J 2
(4090 4335);
DISPLAY 0.617021 (4090 4335);
PAINT MONO (4090 4335);
FORCEPROP 2 LASTPIN (4100 4025) $PN 37
J 2
(4090 4035);
DISPLAY 0.617021 (4090 4035);
PAINT MONO (4090 4035);
FORCEPROP 2 LASTPIN (4950 3825) $PN 5
J 0
(4960 3835);
DISPLAY 0.617021 (4960 3835);
PAINT MONO (4960 3835);
FORCEPROP 2 LASTPIN (4950 3775) $PN 7_9-20_24
J 0
(4960 3785);
DISPLAY 0.617021 (4960 3785);
PAINT MONO (4960 3785);
FORCEPROP 2 LASTPIN (4950 3725) $PN 40
J 0
(4960 3735);
DISPLAY 0.617021 (4960 3735);
PAINT MONO (4960 3735);
FORCEPROP 2 LASTPIN (4950 4425) $PN 32
J 0
(4960 4435);
DISPLAY 0.617021 (4960 4435);
PAINT MONO (4960 4435);
FORCEPROP 2 LASTPIN (4100 4975) $PN 4
J 2
(4090 4985);
DISPLAY 0.617021 (4090 4985);
PAINT MONO (4090 4985);
FORCEPROP 2 LASTPIN (4100 3725) $PN 34
J 2
(4090 3735);
DISPLAY 0.617021 (4090 3735);
PAINT MONO (4090 3735);
FORCEPROP 2 LASTPIN (4100 4225) $PN 39
J 2
(4090 4235);
DISPLAY 0.617021 (4090 4235);
PAINT MONO (4090 4235);
FORCEPROP 2 LASTPIN (4950 4325) $PN 10_19
J 0
(4960 4335);
DISPLAY 0.617021 (4960 4335);
PAINT MONO (4960 4335);
FORCEPROP 2 LASTPIN (4100 3825) $PN 36
J 2
(4090 3835);
DISPLAY 0.617021 (4090 3835);
PAINT MONO (4090 3835);
FORCEPROP 2 LASTPIN (4100 4675) $PN 3
J 2
(4090 4685);
DISPLAY 0.617021 (4090 4685);
PAINT MONO (4090 4685);
FORCEPROP 2 LASTPIN (4950 4975) $PN 25_29
J 0
(4960 4985);
DISPLAY 0.617021 (4960 4985);
PAINT MONO (4960 4985);
FORCEPROP 2 LASTPIN (4950 4925) $PN 30
J 0
(4960 4935);
DISPLAY 0.617021 (4960 4935);
PAINT MONO (4960 4935);
FORCEPROP 2 LASTPIN (4950 4075) $PN 1
J 0
(4960 4085);
DISPLAY 0.617021 (4960 4085);
PAINT MONO (4960 4085);
FORCEPROP 2 LAST CDS_LIB pure_quanta
J 0
(4550 4325);
DISPLAY INVISIBLE (4550 4325);
FORCEPROP 1 LAST CDS_LMAN_SYM_OUTLINE -300,700,250,-650
J 0
(4550 4325);
DISPLAY 0.468085 (4550 4325);
PAINT GREEN (4550 4325);
DISPLAY INVISIBLE (4550 4325);
FORCEPROP 1 LAST NEEDS_NO_SIZE TRUE
J 0
(4550 4325);
DISPLAY 0.723404 (4550 4325);
PAINT GREEN (4550 4325);
DISPLAY INVISIBLE (4550 4325);
FORCEPROP 1 LAST PATH I20
J 0
(4550 4325);
DISPLAY 0.723404 (4550 4325);
PAINT GREEN (4550 4325);
DISPLAY INVISIBLE (4550 4325);
FORCEPROP 2 LAST $SEC 1
J 0
(4250 5250);
DISPLAY 0.680851 (4250 5250);
PAINT MONO (4250 5250);
DISPLAY INVISIBLE (4250 5250);
FORCEPROP 2 LAST CDS_SEC 1
J 0
(4250 5250);
DISPLAY 1.021277 (4250 5250);
DISPLAY INVISIBLE (4250 5250);
FORCEADD UNIVERSAL_GND..1
(2525 4050);
FORCEPROP 3 LASTPIN (2525 4100) SIG_NAME GND\g
J 0
(2535 4110);
DISPLAY 0.659574 (2535 4110);
PAINT MONO (2535 4110);
DISPLAY INVISIBLE (2535 4110);
FORCEPROP 2 LAST CDS_LIB logical_power
J 0
(2525 4050);
PAINT MONO (2525 4050);
DISPLAY INVISIBLE (2525 4050);
FORCEPROP 1 LAST HDL_POWER GND
J 1
(2550 3975);
DISPLAY 0.872340 (2550 3975);
PAINT GREEN (2550 3975);
DISPLAY INVISIBLE (2550 3975);
FORCEPROP 1 LAST PATH I21
J 0
(2600 4050);
DISPLAY 0.872340 (2600 4050);
PAINT AQUA (2600 4050);
DISPLAY INVISIBLE (2600 4050);
FORCEADD OFFPAGE..1
(3100 4225);
FORCEPROP 2 LAST $XR6 272 
J 0
(2098 4225);
DISPLAY 0.638298 (2098 4225);
PAINT MONO (2098 4225);
FORCEPROP 2 LAST $XR5 271 
J 0
(2218 4225);
DISPLAY 0.638298 (2218 4225);
PAINT MONO (2218 4225);
FORCEPROP 2 LAST $XR4 270 
J 0
(2338 4225);
DISPLAY 0.638298 (2338 4225);
PAINT MONO (2338 4225);
FORCEPROP 2 LAST $XR3 269 
J 0
(2458 4225);
DISPLAY 0.638298 (2458 4225);
PAINT MONO (2458 4225);
FORCEPROP 2 LAST $XR2 268 
J 0
(2578 4225);
DISPLAY 0.638298 (2578 4225);
PAINT MONO (2578 4225);
FORCEPROP 2 LAST $XR1 267 
J 0
(2698 4225);
DISPLAY 0.638298 (2698 4225);
PAINT MONO (2698 4225);
FORCEPROP 2 LAST $XR0 266 
J 0
(2818 4225);
DISPLAY 0.638298 (2818 4225);
PAINT MONO (2818 4225);
FORCEPROP 2 LAST CDS_LIB standard
J 0
(3100 4225);
DISPLAY INVISIBLE (3100 4225);
FORCEPROP 1 LAST OFFPAGE TRUE
J 0
(3425 4100);
DISPLAY 0.872340 (3425 4100);
PAINT GREEN (3425 4100);
DISPLAY INVISIBLE (3425 4100);
FORCEPROP 1 LAST COMMENT_BODY TRUE
J 0
(3225 4125);
DISPLAY 0.872340 (3225 4125);
PAINT GREEN (3225 4125);
DISPLAY INVISIBLE (3225 4125);
FORCEPROP 2 LAST PATH I22
J 0
(2825 4275);
DISPLAY 1.021277 (2825 4275);
DISPLAY INVISIBLE (2825 4275);
FORCEADD OFFPAGE..5
(3100 4325);
FORCEPROP 2 LAST $XR0 266 
J 0
(2845 4325);
DISPLAY 0.638298 (2845 4325);
PAINT MONO (2845 4325);
FORCEPROP 2 LAST CDS_LIB standard
J 0
(3100 4325);
DISPLAY INVISIBLE (3100 4325);
FORCEPROP 1 LAST OFFPAGE TRUE
J 0
(3425 4200);
DISPLAY 0.872340 (3425 4200);
PAINT GREEN (3425 4200);
DISPLAY INVISIBLE (3425 4200);
FORCEPROP 1 LAST COMMENT_BODY TRUE
J 0
(3200 4250);
DISPLAY 0.872340 (3200 4250);
PAINT GREEN (3200 4250);
DISPLAY INVISIBLE (3200 4250);
FORCEPROP 2 LAST PATH I23
J 0
(2850 4375);
DISPLAY 1.021277 (2850 4375);
DISPLAY INVISIBLE (2850 4375);
FORCEADD UNIVERSAL_GND..1
(3025 4575);
FORCEPROP 3 LASTPIN (3025 4625) SIG_NAME GND\g
J 0
(3035 4635);
DISPLAY 0.659574 (3035 4635);
PAINT MONO (3035 4635);
DISPLAY INVISIBLE (3035 4635);
FORCEPROP 2 LAST CDS_LIB logical_power
J 0
(3025 4575);
PAINT MONO (3025 4575);
DISPLAY INVISIBLE (3025 4575);
FORCEPROP 1 LAST HDL_POWER GND
J 1
(3050 4500);
DISPLAY 0.872340 (3050 4500);
PAINT GREEN (3050 4500);
DISPLAY INVISIBLE (3050 4500);
FORCEPROP 1 LAST PATH I24
J 0
(3100 4575);
DISPLAY 0.872340 (3100 4575);
PAINT AQUA (3100 4575);
DISPLAY INVISIBLE (3100 4575);
FORCEADD Q_CAP..1
(3025 4825);
FORCEPROP 1 LAST PART_NUMBER CH5222KEB01
J 0
(3075 4650);
DISPLAY 0.617021 (3075 4650);
PAINT BLUE (3075 4650);
DISPLAY INVISIBLE (3075 4650);
FORCEPROP 1 LAST MATERIAL X6S
J 0
(3075 4750);
DISPLAY 0.617021 (3075 4750);
PAINT SKYBLUE (3075 4750);
FORCEPROP 1 LAST TOLERANCE 10%
J 0
(3075 4800);
DISPLAY 0.617021 (3075 4800);
PAINT SKYBLUE (3075 4800);
FORCEPROP 1 LAST VALUE 2.2UF
J 0
(3075 4900);
DISPLAY 0.617021 (3075 4900);
PAINT SKYBLUE (3075 4900);
FORCEPROP 1 LAST VOLTAGE 10V
J 0
(3075 4850);
DISPLAY 0.617021 (3075 4850);
PAINT SKYBLUE (3075 4850);
FORCEPROP 1 LAST PACK_TYPE C0402
J 0
(3075 4700);
DISPLAY 0.617021 (3075 4700);
PAINT SKYBLUE (3075 4700);
FORCEPROP 1 LAST LOCATION PC271
J 0
(3075 4950);
DISPLAY 0.617021 (3075 4950);
PAINT AQUA (3075 4950);
FORCEPROP 1 LASTPIN (3025 4925) $PN 1
J 0
(3035 4905);
DISPLAY 0.617021 (3035 4905);
PAINT MONO (3035 4905);
FORCEPROP 1 LASTPIN (3025 4725) $PN 2
J 0
(3035 4705);
DISPLAY 0.617021 (3035 4705);
PAINT MONO (3035 4705);
FORCEPROP 2 LAST CDS_LIB pure_quanta
J 0
(3025 4825);
DISPLAY INVISIBLE (3025 4825);
FORCEPROP 1 LAST PATH I25
J 0
(3075 4975);
DISPLAY 0.978723 (3075 4975);
PAINT WHITE (3075 4975);
DISPLAY INVISIBLE (3075 4975);
FORCEPROP 1 LAST LOCATION PC271
J 0
(3075 5000);
DISPLAY 1.021277 (3075 5000);
PAINT AQUA (3075 5000);
DISPLAY INVISIBLE (3075 5000);
FORCEPROP 0 LAST $SEC 1
J 0
(3075 5000);
DISPLAY 0.680851 (3075 5000);
PAINT MONO (3075 5000);
DISPLAY INVISIBLE (3075 5000);
FORCEPROP 0 LAST CDS_SEC 1
J 0
(3075 5000);
DISPLAY 1.021277 (3075 5000);
DISPLAY INVISIBLE (3075 5000);
FORCEADD Q_CAP..2
(3350 4125);
FORCEPROP 1 LAST PART_NUMBER CH4104K1B00
J 1
(3650 4150);
DISPLAY 0.617021 (3650 4150);
PAINT BLUE (3650 4150);
DISPLAY INVISIBLE (3650 4150);
FORCEPROP 1 LAST VOLTAGE 25V
J 0
(3675 4125);
DISPLAY 0.617021 (3675 4125);
PAINT SKYBLUE (3675 4125);
FORCEPROP 1 LAST MATERIAL X7R
J 0
(3800 4150);
DISPLAY 0.617021 (3800 4150);
PAINT SKYBLUE (3800 4150);
FORCEPROP 1 LAST TOLERANCE 10%
J 2
(3950 4150);
DISPLAY 0.617021 (3950 4150);
PAINT SKYBLUE (3950 4150);
FORCEPROP 1 LAST PACK_TYPE 0402
J 1
(3800 4125);
DISPLAY 0.617021 (3800 4125);
PAINT SKYBLUE (3800 4125);
FORCEPROP 1 LAST VALUE 0.1UF
J 2
(3650 4125);
DISPLAY 0.617021 (3650 4125);
PAINT SKYBLUE (3650 4125);
FORCEPROP 1 LAST LOCATION PC1341
J 1
(3150 4125);
DISPLAY 0.617021 (3150 4125);
PAINT AQUA (3150 4125);
FORCEPROP 1 LASTPIN (3250 4125) $PN 1
J 0
(3240 4140);
DISPLAY 0.617021 (3240 4140);
FORCEPROP 1 LASTPIN (3450 4125) $PN 2
J 0
(3435 4140);
DISPLAY 0.617021 (3435 4140);
FORCEPROP 2 LAST CDS_LIB pure_quanta
J 0
(3350 4125);
PAINT MONO (3350 4125);
DISPLAY INVISIBLE (3350 4125);
FORCEPROP 1 LAST PATH I26
J 0
(3350 4325);
DISPLAY 0.978723 (3350 4325);
PAINT WHITE (3350 4325);
DISPLAY INVISIBLE (3350 4325);
FORCEPROP 2 LAST $SEC 1
J 0
(3350 4375);
DISPLAY 0.680851 (3350 4375);
PAINT MONO (3350 4375);
DISPLAY INVISIBLE (3350 4375);
FORCEPROP 2 LAST CDS_SEC 1
J 0
(3350 4375);
DISPLAY 1.021277 (3350 4375);
DISPLAY INVISIBLE (3350 4375);
FORCEADD Q_RES..2
(3025 5325);
FORCEPROP 1 LAST PART_NUMBER CS-2202FB01
J 0
(3065 5200);
DISPLAY 0.617021 (3065 5200);
PAINT BLUE (3065 5200);
DISPLAY INVISIBLE (3065 5200);
FORCEPROP 1 LAST WATTAGE 1/16W
J 0
(3065 5300);
DISPLAY 0.617021 (3065 5300);
PAINT SKYBLUE (3065 5300);
FORCEPROP 1 LAST MATERIAL CHIP
J 0
(3065 5250);
DISPLAY 0.617021 (3065 5250);
PAINT SKYBLUE (3065 5250);
FORCEPROP 1 LAST TOLERANCE 1%
J 0
(3070 5350);
DISPLAY 0.617021 (3070 5350);
PAINT SKYBLUE (3070 5350);
FORCEPROP 1 LAST VALUE 2.2
J 0
(3070 5400);
DISPLAY 0.617021 (3070 5400);
PAINT SKYBLUE (3070 5400);
FORCEPROP 1 LAST PACK_TYPE 0402LF
J 0
(3065 5150);
DISPLAY 0.617021 (3065 5150);
PAINT SKYBLUE (3065 5150);
FORCEPROP 1 LAST LOCATION PR147
J 0
(3070 5450);
DISPLAY 0.617021 (3070 5450);
PAINT AQUA (3070 5450);
FORCEPROP 1 LASTPIN (3025 5425) $PN 1
J 0
(3030 5387);
DISPLAY 0.617021 (3030 5387);
PAINT MONO (3030 5387);
FORCEPROP 1 LASTPIN (3025 5225) $PN 2
J 0
(3030 5235);
DISPLAY 0.617021 (3030 5235);
PAINT MONO (3030 5235);
FORCEPROP 2 LAST CDS_LIB pure_quanta
J 0
(3025 5325);
DISPLAY INVISIBLE (3025 5325);
FORCEPROP 1 LAST PATH I27
J 0
(3075 5500);
DISPLAY 0.978723 (3075 5500);
PAINT WHITE (3075 5500);
DISPLAY INVISIBLE (3075 5500);
FORCEPROP 1 LAST LOCATION PR147
J 0
(3075 5500);
DISPLAY 1.021277 (3075 5500);
PAINT AQUA (3075 5500);
DISPLAY INVISIBLE (3075 5500);
FORCEPROP 0 LAST $SEC 1
J 0
(3075 5500);
DISPLAY 0.680851 (3075 5500);
PAINT MONO (3075 5500);
DISPLAY INVISIBLE (3075 5500);
FORCEPROP 0 LAST CDS_SEC 1
J 0
(3075 5500);
DISPLAY 1.021277 (3075 5500);
DISPLAY INVISIBLE (3075 5500);
FORCEADD VCC15..1
(3025 5650);
FORCEPROP 3 LASTPIN (3025 5600) SIG_NAME PVCCIN_CPU0_PVCC\g
J 0
(3035 5610);
DISPLAY 0.659574 (3035 5610);
PAINT MONO (3035 5610);
DISPLAY INVISIBLE (3035 5610);
FORCEPROP 1 LAST HDL_POWER PVCCIN_CPU0_PVCC
J 1
(3025 5700);
DISPLAY 0.617021 (3025 5700);
PAINT GREEN (3025 5700);
FORCEPROP 2 LAST CDS_LIB logical_power
J 0
(3025 5650);
DISPLAY INVISIBLE (3025 5650);
FORCEPROP 1 LAST PATH I28
J 0
(3075 5675);
DISPLAY 0.872340 (3075 5675);
PAINT AQUA (3075 5675);
DISPLAY INVISIBLE (3075 5675);
FORCEADD UNIVERSAL_GND..1
(3450 5100);
FORCEPROP 3 LASTPIN (3450 5150) SIG_NAME GND\g
J 0
(3460 5160);
DISPLAY 0.659574 (3460 5160);
PAINT MONO (3460 5160);
DISPLAY INVISIBLE (3460 5160);
FORCEPROP 2 LAST CDS_LIB logical_power
J 0
(3450 5100);
PAINT MONO (3450 5100);
DISPLAY INVISIBLE (3450 5100);
FORCEPROP 1 LAST HDL_POWER GND
J 1
(3475 5025);
DISPLAY 0.872340 (3475 5025);
PAINT GREEN (3475 5025);
DISPLAY INVISIBLE (3475 5025);
FORCEPROP 1 LAST PATH I29
J 0
(3525 5100);
DISPLAY 0.872340 (3525 5100);
PAINT AQUA (3525 5100);
DISPLAY INVISIBLE (3525 5100);
FORCEADD UNIVERSAL_GND..1
(2500 1225);
FORCEPROP 3 LASTPIN (2500 1275) SIG_NAME GND\g
J 0
(2510 1285);
DISPLAY 0.659574 (2510 1285);
PAINT MONO (2510 1285);
DISPLAY INVISIBLE (2510 1285);
FORCEPROP 2 LAST CDS_LIB logical_power
J 0
(2500 1225);
PAINT MONO (2500 1225);
DISPLAY INVISIBLE (2500 1225);
FORCEPROP 1 LAST HDL_POWER GND
J 1
(2525 1150);
DISPLAY 0.872340 (2525 1150);
PAINT GREEN (2525 1150);
DISPLAY INVISIBLE (2525 1150);
FORCEPROP 1 LAST PATH I3
J 0
(2575 1225);
DISPLAY 0.872340 (2575 1225);
PAINT AQUA (2575 1225);
DISPLAY INVISIBLE (2575 1225);
FORCEADD Q_CAP..1
(3450 5325);
FORCEPROP 1 LAST PART_NUMBER CH5222KEB01
J 0
(3500 5200);
DISPLAY 0.617021 (3500 5200);
PAINT BLUE (3500 5200);
DISPLAY INVISIBLE (3500 5200);
FORCEPROP 1 LAST MATERIAL X6S
J 0
(3500 5250);
DISPLAY 0.617021 (3500 5250);
PAINT SKYBLUE (3500 5250);
FORCEPROP 1 LAST TOLERANCE 10%
J 0
(3500 5300);
DISPLAY 0.617021 (3500 5300);
PAINT SKYBLUE (3500 5300);
FORCEPROP 1 LAST VALUE 2.2UF
J 0
(3500 5400);
DISPLAY 0.617021 (3500 5400);
PAINT SKYBLUE (3500 5400);
FORCEPROP 1 LAST VOLTAGE 10V
J 0
(3500 5350);
DISPLAY 0.617021 (3500 5350);
PAINT SKYBLUE (3500 5350);
FORCEPROP 1 LAST PACK_TYPE C0402
J 0
(3500 5150);
DISPLAY 0.617021 (3500 5150);
PAINT SKYBLUE (3500 5150);
FORCEPROP 1 LAST LOCATION PC273_P0_3
J 0
(3500 5450);
DISPLAY 0.617021 (3500 5450);
PAINT AQUA (3500 5450);
FORCEPROP 1 LASTPIN (3450 5425) $PN 1
J 0
(3460 5405);
DISPLAY 0.617021 (3460 5405);
PAINT MONO (3460 5405);
FORCEPROP 1 LASTPIN (3450 5225) $PN 2
J 0
(3460 5205);
DISPLAY 0.617021 (3460 5205);
PAINT MONO (3460 5205);
FORCEPROP 2 LAST CDS_LIB pure_quanta
J 0
(3450 5325);
DISPLAY INVISIBLE (3450 5325);
FORCEPROP 1 LAST PATH I30
J 0
(3500 5475);
DISPLAY 0.978723 (3500 5475);
PAINT WHITE (3500 5475);
DISPLAY INVISIBLE (3500 5475);
FORCEPROP 1 LAST LOCATION PC273_P0_3
J 0
(3500 5500);
DISPLAY 1.021277 (3500 5500);
PAINT AQUA (3500 5500);
DISPLAY INVISIBLE (3500 5500);
FORCEPROP 0 LAST $SEC 1
J 0
(3500 5500);
DISPLAY 0.680851 (3500 5500);
PAINT MONO (3500 5500);
DISPLAY INVISIBLE (3500 5500);
FORCEPROP 0 LAST CDS_SEC 1
J 0
(3500 5500);
DISPLAY 1.021277 (3500 5500);
DISPLAY INVISIBLE (3500 5500);
FORCEADD UNIVERSAL_GND..1
(5175 775);
FORCEPROP 3 LASTPIN (5175 825) SIG_NAME GND\g
J 0
(5185 835);
DISPLAY 0.659574 (5185 835);
PAINT MONO (5185 835);
DISPLAY INVISIBLE (5185 835);
FORCEPROP 2 LAST CDS_LIB logical_power
J 0
(5175 775);
PAINT MONO (5175 775);
DISPLAY INVISIBLE (5175 775);
FORCEPROP 1 LAST HDL_POWER GND
J 1
(5200 700);
DISPLAY 0.872340 (5200 700);
PAINT GREEN (5200 700);
DISPLAY INVISIBLE (5200 700);
FORCEPROP 1 LAST PATH I31
J 0
(5250 775);
DISPLAY 0.872340 (5250 775);
PAINT AQUA (5250 775);
DISPLAY INVISIBLE (5250 775);
FORCEADD OFFPAGE..6
(5850 1250);
FORCEPROP 2 LAST $XR0 268 
J 0
(5570 1250);
DISPLAY 0.638298 (5570 1250);
PAINT MONO (5570 1250);
FORCEPROP 1 LAST COMMENT_BODY TRUE
J 0
(5950 1175);
DISPLAY 0.872340 (5950 1175);
PAINT GREEN (5950 1175);
DISPLAY INVISIBLE (5950 1175);
FORCEPROP 1 LAST OFFPAGE TRUE
J 0
(6175 1125);
DISPLAY 0.872340 (6175 1125);
PAINT GREEN (6175 1125);
DISPLAY INVISIBLE (6175 1125);
FORCEPROP 2 LAST CDS_LIB standard
J 0
(5850 1250);
DISPLAY INVISIBLE (5850 1250);
FORCEPROP 2 LAST PATH I32
J 0
(5575 1300);
DISPLAY 1.021277 (5575 1300);
DISPLAY INVISIBLE (5575 1300);
FORCEADD Q_INDUCTOR4P_14..1
(6950 1375);
FORCEPROP 1 LAST PART_NUMBER CV+15^0TZ04
J 0
(6725 1535);
DISPLAY 0.617021 (6725 1535);
PAINT BLUE (6725 1535);
DISPLAY INVISIBLE (6725 1535);
FORCEPROP 2 LAST PART_TYPE SMLF
J 0
(6725 1725);
DISPLAY 1.021277 (6725 1725);
FORCEPROP 2 LAST VALUE 150NH
J 0
(6725 1675);
DISPLAY 0.617021 (6725 1675);
PAINT SKYBLUE (6725 1675);
FORCEPROP 1 LAST MATERIAL IND
J 0
(6725 1585);
DISPLAY 0.617021 (6725 1585);
PAINT SKYBLUE (6725 1585);
FORCEPROP 1 LAST LOCATION PL11
J 0
(6725 1630);
DISPLAY 0.617021 (6725 1630);
PAINT AQUA (6725 1630);
FORCEPROP 2 LASTPIN (6550 1500) $PN 1
J 2
(6540 1510);
DISPLAY 0.617021 (6540 1510);
PAINT MONO (6540 1510);
FORCEPROP 2 LASTPIN (6550 1250) $PN 2
J 2
(6540 1260);
DISPLAY 0.617021 (6540 1260);
PAINT MONO (6540 1260);
FORCEPROP 2 LASTPIN (7350 1250) $PN 3
J 0
(7360 1260);
DISPLAY 0.617021 (7360 1260);
PAINT MONO (7360 1260);
FORCEPROP 2 LASTPIN (7350 1500) $PN 4
J 0
(7360 1510);
DISPLAY 0.617021 (7360 1510);
PAINT MONO (7360 1510);
FORCEPROP 2 LAST SEC_TYPE 
J 0
(6725 1775);
DISPLAY 1.021277 (6725 1775);
DISPLAY INVISIBLE (6725 1775);
FORCEPROP 2 LAST CDS_LIB pure_quanta
J 0
(6950 1375);
DISPLAY INVISIBLE (6950 1375);
FORCEPROP 1 LAST NEEDS_NO_SIZE TRUE
J 0
(6950 1375);
DISPLAY 0.468085 (6950 1375);
PAINT GREEN (6950 1375);
DISPLAY INVISIBLE (6950 1375);
FORCEPROP 1 LAST PATH I33
J 0
(7150 1530);
DISPLAY 0.723404 (7150 1530);
PAINT GREEN (7150 1530);
DISPLAY INVISIBLE (7150 1530);
FORCEPROP 2 LAST SEC 1
J 0
(6725 1775);
DISPLAY 0.680851 (6725 1775);
PAINT MONO (6725 1775);
DISPLAY INVISIBLE (6725 1775);
FORCEADD Q_CAP..1
R 2
(6500 1775);
FORCEPROP 1 LAST PART_NUMBER CH4106K1B01
J 2
(6450 1725);
DISPLAY 0.617021 (6450 1725);
PAINT BLUE (6450 1725);
DISPLAY INVISIBLE (6450 1725);
FORCEPROP 1 LAST MATERIAL X7R
J 2
(6450 1750);
DISPLAY 0.617021 (6450 1750);
PAINT SKYBLUE (6450 1750);
FORCEPROP 1 LAST TOLERANCE 10%
J 2
(6450 1775);
DISPLAY 0.617021 (6450 1775);
PAINT SKYBLUE (6450 1775);
FORCEPROP 1 LAST VALUE 100NF
J 2
(6450 1825);
DISPLAY 0.617021 (6450 1825);
PAINT SKYBLUE (6450 1825);
FORCEPROP 1 LAST VOLTAGE 50V
J 2
(6450 1800);
DISPLAY 0.617021 (6450 1800);
PAINT SKYBLUE (6450 1800);
FORCEPROP 1 LAST PACK_TYPE C0402
J 2
(6450 1700);
DISPLAY 0.617021 (6450 1700);
PAINT SKYBLUE (6450 1700);
FORCEPROP 1 LAST LOCATION PC278
J 2
(6450 1850);
DISPLAY 0.617021 (6450 1850);
PAINT AQUA (6450 1850);
FORCEPROP 1 LASTPIN (6500 1875) $PN 1
J 2
(6490 1855);
DISPLAY 0.617021 (6490 1855);
FORCEPROP 1 LASTPIN (6500 1675) $PN 2
J 2
(6490 1655);
DISPLAY 0.617021 (6490 1655);
FORCEPROP 2 LAST CDS_LIB pure_quanta
J 2
(6500 1775);
PAINT MONO (6500 1775);
DISPLAY INVISIBLE (6500 1775);
FORCEPROP 1 LAST PATH I34
J 2
(6450 1925);
DISPLAY 0.978723 (6450 1925);
PAINT WHITE (6450 1925);
DISPLAY INVISIBLE (6450 1925);
FORCEPROP 2 LAST $SEC 1
J 0
(6450 1975);
DISPLAY 0.680851 (6450 1975);
PAINT MONO (6450 1975);
DISPLAY INVISIBLE (6450 1975);
FORCEPROP 2 LAST CDS_SEC 1
J 0
(6450 1975);
DISPLAY 1.021277 (6450 1975);
DISPLAY INVISIBLE (6450 1975);
FORCEADD Q_CAP..1
(5325 2400);
FORCEPROP 1 LAST PART_NUMBER TMP_QCH2336K1B12
J 0
(5375 2250);
DISPLAY 0.617021 (5375 2250);
PAINT BLUE (5375 2250);
DISPLAY INVISIBLE (5375 2250);
FORCEPROP 1 LAST VALUE 3300PF
J 0
(5375 2500);
DISPLAY 0.617021 (5375 2500);
PAINT SKYBLUE (5375 2500);
FORCEPROP 1 LAST MATERIAL X7R
J 0
(5375 2350);
DISPLAY 0.617021 (5375 2350);
PAINT SKYBLUE (5375 2350);
FORCEPROP 1 LAST TOLERANCE 10%
J 0
(5375 2400);
DISPLAY 0.617021 (5375 2400);
PAINT SKYBLUE (5375 2400);
FORCEPROP 1 LAST VOLTAGE 50V
J 0
(5375 2450);
DISPLAY 0.617021 (5375 2450);
PAINT SKYBLUE (5375 2450);
FORCEPROP 1 LAST PACK_TYPE 0402
J 0
(5375 2300);
DISPLAY 0.617021 (5375 2300);
PAINT SKYBLUE (5375 2300);
FORCEPROP 1 LAST LOCATION PC274_P0_4
J 0
(5375 2550);
DISPLAY 0.617021 (5375 2550);
PAINT AQUA (5375 2550);
FORCEPROP 1 LASTPIN (5325 2500) $PN 1
J 0
(5335 2480);
DISPLAY 0.617021 (5335 2480);
PAINT MONO (5335 2480);
FORCEPROP 1 LASTPIN (5325 2300) $PN 2
J 0
(5335 2280);
DISPLAY 0.617021 (5335 2280);
PAINT MONO (5335 2280);
FORCEPROP 2 LAST CDS_LIB pure_quanta
J 0
(5325 2400);
DISPLAY INVISIBLE (5325 2400);
FORCEPROP 1 LAST PATH I35
J 0
(5375 2550);
DISPLAY 0.978723 (5375 2550);
PAINT WHITE (5375 2550);
DISPLAY INVISIBLE (5375 2550);
FORCEPROP 1 LAST LOCATION PC274_P0_4
J 0
(5375 2600);
DISPLAY 1.021277 (5375 2600);
PAINT AQUA (5375 2600);
DISPLAY INVISIBLE (5375 2600);
FORCEPROP 0 LAST $SEC 1
J 0
(5375 2600);
DISPLAY 0.680851 (5375 2600);
PAINT MONO (5375 2600);
DISPLAY INVISIBLE (5375 2600);
FORCEPROP 0 LAST CDS_SEC 1
J 0
(5375 2600);
DISPLAY 1.021277 (5375 2600);
DISPLAY INVISIBLE (5375 2600);
FORCEADD Q_RES..1
(5775 1950);
FORCEPROP 1 LAST PART_NUMBER CS-3302FB01
J 0
(5675 2000);
DISPLAY 0.617021 (5675 2000);
PAINT BLUE (5675 2000);
DISPLAY INVISIBLE (5675 2000);
FORCEPROP 1 LAST VALUE 3.3
J 2
(6000 1950);
DISPLAY 0.617021 (6000 1950);
PAINT SKYBLUE (6000 1950);
FORCEPROP 1 LAST TOLERANCE 1%
J 0
(6025 1950);
DISPLAY 0.617021 (6025 1950);
PAINT SKYBLUE (6025 1950);
FORCEPROP 1 LAST WATTAGE 1/16W
J 2
(5900 2025);
DISPLAY 0.617021 (5900 2025);
PAINT SKYBLUE (5900 2025);
FORCEPROP 1 LAST MATERIAL CHIP
J 0
(5675 2050);
DISPLAY 0.617021 (5675 2050);
PAINT SKYBLUE (5675 2050);
FORCEPROP 1 LAST PACK_TYPE 0402LF
J 0
(5675 2025);
DISPLAY 0.617021 (5675 2025);
PAINT SKYBLUE (5675 2025);
FORCEPROP 1 LAST LOCATION PR1768
J 0
(5525 1950);
DISPLAY 0.617021 (5525 1950);
PAINT AQUA (5525 1950);
FORCEPROP 1 LASTPIN (5675 1950) $PN 1
J 0
(5687 1962);
DISPLAY 0.617021 (5687 1962);
FORCEPROP 1 LASTPIN (5875 1950) $PN 2
J 0
(5837 1962);
DISPLAY 0.617021 (5837 1962);
FORCEPROP 2 LAST CDS_LIB pure_quanta
J 0
(5775 1950);
PAINT MONO (5775 1950);
DISPLAY INVISIBLE (5775 1950);
FORCEPROP 1 LAST PATH I36
J 0
(5725 2100);
DISPLAY 0.978723 (5725 2100);
PAINT WHITE (5725 2100);
DISPLAY INVISIBLE (5725 2100);
FORCEPROP 2 LAST $SEC 1
J 0
(5725 2150);
DISPLAY 0.680851 (5725 2150);
PAINT MONO (5725 2150);
DISPLAY INVISIBLE (5725 2150);
FORCEPROP 2 LAST CDS_SEC 1
J 0
(5725 2150);
DISPLAY 1.021277 (5725 2150);
DISPLAY INVISIBLE (5725 2150);
FORCEADD UNIVERSAL_GND..1
(5200 3600);
FORCEPROP 3 LASTPIN (5200 3650) SIG_NAME GND\g
J 0
(5210 3660);
DISPLAY 0.659574 (5210 3660);
PAINT MONO (5210 3660);
DISPLAY INVISIBLE (5210 3660);
FORCEPROP 2 LAST CDS_LIB logical_power
J 0
(5200 3600);
PAINT MONO (5200 3600);
DISPLAY INVISIBLE (5200 3600);
FORCEPROP 1 LAST HDL_POWER GND
J 1
(5225 3525);
DISPLAY 0.872340 (5225 3525);
PAINT GREEN (5225 3525);
DISPLAY INVISIBLE (5225 3525);
FORCEPROP 1 LAST PATH I37
J 0
(5275 3600);
DISPLAY 0.872340 (5275 3600);
PAINT AQUA (5275 3600);
DISPLAY INVISIBLE (5275 3600);
FORCEADD Q_CAP..1
(5725 2400);
FORCEPROP 1 LAST PART_NUMBER CH5103KEB01
J 0
(5775 2250);
DISPLAY 0.617021 (5775 2250);
PAINT BLUE (5775 2250);
DISPLAY INVISIBLE (5775 2250);
FORCEPROP 1 LAST TOLERANCE 10%
J 0
(5775 2400);
DISPLAY 0.617021 (5775 2400);
PAINT SKYBLUE (5775 2400);
FORCEPROP 1 LAST MATERIAL X6S
J 0
(5775 2350);
DISPLAY 0.617021 (5775 2350);
PAINT SKYBLUE (5775 2350);
FORCEPROP 1 LAST VALUE 1UF
J 0
(5775 2500);
DISPLAY 0.617021 (5775 2500);
PAINT SKYBLUE (5775 2500);
FORCEPROP 1 LAST VOLTAGE 16V
J 0
(5775 2450);
DISPLAY 0.617021 (5775 2450);
PAINT SKYBLUE (5775 2450);
FORCEPROP 1 LAST PACK_TYPE C0402
J 0
(5775 2300);
DISPLAY 0.617021 (5775 2300);
PAINT SKYBLUE (5775 2300);
FORCEPROP 1 LAST LOCATION PC276_P0_4
J 0
(5775 2550);
DISPLAY 0.617021 (5775 2550);
PAINT AQUA (5775 2550);
FORCEPROP 1 LASTPIN (5725 2500) $PN 1
J 0
(5735 2480);
DISPLAY 0.617021 (5735 2480);
PAINT MONO (5735 2480);
FORCEPROP 1 LASTPIN (5725 2300) $PN 2
J 0
(5735 2280);
DISPLAY 0.617021 (5735 2280);
PAINT MONO (5735 2280);
FORCEPROP 2 LAST CDS_LIB pure_quanta
J 0
(5725 2400);
DISPLAY INVISIBLE (5725 2400);
FORCEPROP 1 LAST PATH I38
J 0
(5775 2550);
DISPLAY 0.978723 (5775 2550);
PAINT WHITE (5775 2550);
DISPLAY INVISIBLE (5775 2550);
FORCEPROP 1 LAST LOCATION PC276_P0_4
J 0
(5775 2600);
DISPLAY 1.021277 (5775 2600);
PAINT AQUA (5775 2600);
DISPLAY INVISIBLE (5775 2600);
FORCEPROP 0 LAST $SEC 1
J 0
(5775 2600);
DISPLAY 0.680851 (5775 2600);
PAINT MONO (5775 2600);
DISPLAY INVISIBLE (5775 2600);
FORCEPROP 0 LAST CDS_SEC 1
J 0
(5775 2600);
DISPLAY 1.021277 (5775 2600);
DISPLAY INVISIBLE (5775 2600);
FORCEADD Q_CAP..1
(6125 2400);
FORCEPROP 1 LAST PART_NUMBER CH6223MEA01
J 0
(6175 2250);
DISPLAY 0.617021 (6175 2250);
PAINT BLUE (6175 2250);
DISPLAY INVISIBLE (6175 2250);
FORCEPROP 1 LAST PACK_TYPE C0805
J 0
(6175 2300);
DISPLAY 0.617021 (6175 2300);
PAINT SKYBLUE (6175 2300);
FORCEPROP 1 LAST MATERIAL X6S
J 0
(6175 2350);
DISPLAY 0.617021 (6175 2350);
PAINT SKYBLUE (6175 2350);
FORCEPROP 1 LAST TOLERANCE 20%
J 0
(6175 2400);
DISPLAY 0.617021 (6175 2400);
PAINT SKYBLUE (6175 2400);
FORCEPROP 1 LAST VALUE 22UF
J 0
(6175 2500);
DISPLAY 0.617021 (6175 2500);
PAINT SKYBLUE (6175 2500);
FORCEPROP 1 LAST VOLTAGE 16V
J 0
(6175 2450);
DISPLAY 0.617021 (6175 2450);
PAINT SKYBLUE (6175 2450);
FORCEPROP 1 LAST LOCATION PC280_P0_4
J 0
(6175 2550);
DISPLAY 0.617021 (6175 2550);
PAINT AQUA (6175 2550);
FORCEPROP 1 LASTPIN (6125 2500) $PN 1
J 0
(6135 2480);
DISPLAY 0.617021 (6135 2480);
PAINT MONO (6135 2480);
FORCEPROP 1 LASTPIN (6125 2300) $PN 2
J 0
(6135 2280);
DISPLAY 0.617021 (6135 2280);
PAINT MONO (6135 2280);
FORCEPROP 2 LAST CDS_LIB pure_quanta
J 0
(6125 2400);
DISPLAY INVISIBLE (6125 2400);
FORCEPROP 1 LAST PATH I39
J 0
(6175 2550);
DISPLAY 0.978723 (6175 2550);
PAINT WHITE (6175 2550);
DISPLAY INVISIBLE (6175 2550);
FORCEPROP 1 LAST LOCATION PC280_P0_4
J 0
(6175 2600);
DISPLAY 1.021277 (6175 2600);
PAINT AQUA (6175 2600);
DISPLAY INVISIBLE (6175 2600);
FORCEPROP 0 LAST $SEC 1
J 0
(6175 2600);
DISPLAY 0.680851 (6175 2600);
PAINT MONO (6175 2600);
DISPLAY INVISIBLE (6175 2600);
FORCEPROP 0 LAST CDS_SEC 1
J 0
(6175 2600);
DISPLAY 1.021277 (6175 2600);
DISPLAY INVISIBLE (6175 2600);
FORCEADD Q_RES..2
R 2
(2625 3825);
FORCEPROP 1 LAST PART_NUMBER CS28872FB01
J 2
(2585 3700);
DISPLAY 0.617021 (2585 3700);
PAINT BLUE (2585 3700);
DISPLAY INVISIBLE (2585 3700);
FORCEPROP 1 LAST MATERIAL EMPTY
J 2
(2585 3750);
DISPLAY 0.617021 (2585 3750);
PAINT RED (2585 3750);
FORCEPROP 1 LAST TOLERANCE 1%
J 2
(2580 3850);
DISPLAY 0.617021 (2580 3850);
PAINT SKYBLUE (2580 3850);
FORCEPROP 1 LAST VALUE 8.87K
J 2
(2580 3900);
DISPLAY 0.617021 (2580 3900);
PAINT SKYBLUE (2580 3900);
FORCEPROP 1 LAST PACK_TYPE 0402LF
J 2
(2585 3650);
DISPLAY 0.617021 (2585 3650);
PAINT SKYBLUE (2585 3650);
FORCEPROP 1 LAST WATTAGE 1/16W
J 2
(2585 3800);
DISPLAY 0.617021 (2585 3800);
PAINT SKYBLUE (2585 3800);
FORCEPROP 1 LAST LOCATION PR145
J 2
(2580 3950);
DISPLAY 0.617021 (2580 3950);
PAINT AQUA (2580 3950);
FORCEPROP 1 LASTPIN (2625 3925) $PN 1
J 2
(2620 3887);
DISPLAY 0.617021 (2620 3887);
PAINT MONO (2620 3887);
FORCEPROP 1 LASTPIN (2625 3725) $PN 2
J 2
(2620 3735);
DISPLAY 0.617021 (2620 3735);
PAINT MONO (2620 3735);
FORCEPROP 2 LAST CDS_LIB pure_quanta
J 2
(2625 3825);
DISPLAY INVISIBLE (2625 3825);
FORCEPROP 1 LAST PATH I4
J 2
(2575 4000);
DISPLAY 0.978723 (2575 4000);
PAINT WHITE (2575 4000);
DISPLAY INVISIBLE (2575 4000);
FORCEPROP 0 LAST $SEC 1
J 0
(2600 4000);
DISPLAY 0.680851 (2600 4000);
PAINT MONO (2600 4000);
DISPLAY INVISIBLE (2600 4000);
FORCEPROP 0 LAST CDS_SEC 1
J 0
(2600 4000);
DISPLAY 1.021277 (2600 4000);
DISPLAY INVISIBLE (2600 4000);
FORCEADD Q_CAP..1
(6525 2400);
FORCEPROP 1 LAST PART_NUMBER CH6223MEA01
J 0
(6575 2250);
DISPLAY 0.617021 (6575 2250);
PAINT BLUE (6575 2250);
DISPLAY INVISIBLE (6575 2250);
FORCEPROP 1 LAST MATERIAL X6S
J 0
(6575 2350);
DISPLAY 0.617021 (6575 2350);
PAINT SKYBLUE (6575 2350);
FORCEPROP 1 LAST TOLERANCE 20%
J 0
(6575 2400);
DISPLAY 0.617021 (6575 2400);
PAINT SKYBLUE (6575 2400);
FORCEPROP 1 LAST VOLTAGE 16V
J 0
(6575 2450);
DISPLAY 0.617021 (6575 2450);
PAINT SKYBLUE (6575 2450);
FORCEPROP 1 LAST PACK_TYPE C0805
J 0
(6575 2300);
DISPLAY 0.617021 (6575 2300);
PAINT SKYBLUE (6575 2300);
FORCEPROP 1 LAST VALUE 22UF
J 0
(6575 2500);
DISPLAY 0.617021 (6575 2500);
PAINT SKYBLUE (6575 2500);
FORCEPROP 1 LAST LOCATION PC282_P0_4
J 0
(6575 2550);
DISPLAY 0.617021 (6575 2550);
PAINT AQUA (6575 2550);
FORCEPROP 1 LASTPIN (6525 2500) $PN 1
J 0
(6535 2480);
DISPLAY 0.617021 (6535 2480);
PAINT MONO (6535 2480);
FORCEPROP 1 LASTPIN (6525 2300) $PN 2
J 0
(6535 2280);
DISPLAY 0.617021 (6535 2280);
PAINT MONO (6535 2280);
FORCEPROP 2 LAST CDS_LIB pure_quanta
J 0
(6525 2400);
DISPLAY INVISIBLE (6525 2400);
FORCEPROP 1 LAST PATH I40
J 0
(6575 2550);
DISPLAY 0.978723 (6575 2550);
PAINT WHITE (6575 2550);
DISPLAY INVISIBLE (6575 2550);
FORCEPROP 1 LAST LOCATION PC282_P0_4
J 0
(6575 2600);
DISPLAY 1.021277 (6575 2600);
PAINT AQUA (6575 2600);
DISPLAY INVISIBLE (6575 2600);
FORCEPROP 0 LAST $SEC 1
J 0
(6575 2600);
DISPLAY 0.680851 (6575 2600);
PAINT MONO (6575 2600);
DISPLAY INVISIBLE (6575 2600);
FORCEPROP 0 LAST CDS_SEC 1
J 0
(6575 2600);
DISPLAY 1.021277 (6575 2600);
DISPLAY INVISIBLE (6575 2600);
FORCEADD Q_RES..1
(7075 975);
FORCEPROP 1 LAST PART_NUMBER CS00002JB13
J 0
(6950 1025);
DISPLAY 0.617021 (6950 1025);
PAINT BLUE (6950 1025);
DISPLAY INVISIBLE (6950 1025);
FORCEPROP 1 LAST MATERIAL CHIP
J 0
(7350 975);
DISPLAY 0.617021 (7350 975);
PAINT SKYBLUE (7350 975);
FORCEPROP 1 LAST TOLERANCE 5%
J 0
(7275 975);
DISPLAY 0.617021 (7275 975);
PAINT SKYBLUE (7275 975);
FORCEPROP 1 LAST VALUE 0
J 2
(7250 975);
DISPLAY 0.617021 (7250 975);
PAINT SKYBLUE (7250 975);
FORCEPROP 1 LAST PACK_TYPE 0402LF
J 0
(6950 1075);
DISPLAY 0.617021 (6950 1075);
PAINT SKYBLUE (6950 1075);
FORCEPROP 1 LAST WATTAGE 1/16W
J 2
(7325 1075);
DISPLAY 0.617021 (7325 1075);
PAINT SKYBLUE (7325 1075);
FORCEPROP 1 LAST LOCATION PR148
J 0
(6800 975);
DISPLAY 0.617021 (6800 975);
PAINT AQUA (6800 975);
FORCEPROP 1 LASTPIN (6975 975) $PN 1
J 0
(6987 987);
DISPLAY 0.617021 (6987 987);
PAINT MONO (6987 987);
FORCEPROP 1 LASTPIN (7175 975) $PN 2
J 0
(7137 987);
DISPLAY 0.617021 (7137 987);
PAINT MONO (7137 987);
FORCEPROP 2 LAST CDS_LIB pure_quanta
J 0
(7075 975);
DISPLAY INVISIBLE (7075 975);
FORCEPROP 1 LAST PATH I41
J 0
(7025 1125);
DISPLAY 0.978723 (7025 1125);
PAINT WHITE (7025 1125);
DISPLAY INVISIBLE (7025 1125);
FORCEPROP 0 LAST $SEC 1
J 0
(7325 1125);
DISPLAY 0.680851 (7325 1125);
PAINT MONO (7325 1125);
DISPLAY INVISIBLE (7325 1125);
FORCEPROP 0 LAST CDS_SEC 1
J 0
(7325 1125);
DISPLAY 1.021277 (7325 1125);
DISPLAY INVISIBLE (7325 1125);
FORCEADD OFFPAGE..3
(7900 1250);
FORCEPROP 2 LAST $XR0 269 
J 0
(8114 1250);
DISPLAY 0.638298 (8114 1250);
PAINT MONO (8114 1250);
FORCEPROP 1 LAST COMMENT_BODY TRUE
J 0
(7850 1150);
DISPLAY 0.872340 (7850 1150);
PAINT GREEN (7850 1150);
DISPLAY INVISIBLE (7850 1150);
FORCEPROP 1 LAST OFFPAGE TRUE
J 0
(8225 1125);
DISPLAY 0.872340 (8225 1125);
PAINT GREEN (8225 1125);
DISPLAY INVISIBLE (8225 1125);
FORCEPROP 2 LAST CDS_LIB standard
J 0
(7900 1250);
DISPLAY INVISIBLE (7900 1250);
FORCEPROP 2 LAST PATH I42
J 0
(8125 1300);
DISPLAY 1.021277 (8125 1300);
DISPLAY INVISIBLE (8125 1300);
FORCEADD Q_CAP..1
(6900 2400);
FORCEPROP 1 LAST PART_NUMBER CH6223MEA01
J 0
(6950 2250);
DISPLAY 0.617021 (6950 2250);
PAINT BLUE (6950 2250);
DISPLAY INVISIBLE (6950 2250);
FORCEPROP 1 LAST PACK_TYPE C0805
J 0
(6950 2300);
DISPLAY 0.617021 (6950 2300);
PAINT SKYBLUE (6950 2300);
FORCEPROP 1 LAST VALUE 22UF
J 0
(6950 2500);
DISPLAY 0.617021 (6950 2500);
PAINT SKYBLUE (6950 2500);
FORCEPROP 1 LAST TOLERANCE 20%
J 0
(6950 2400);
DISPLAY 0.617021 (6950 2400);
PAINT SKYBLUE (6950 2400);
FORCEPROP 1 LAST MATERIAL X6S
J 0
(6950 2350);
DISPLAY 0.617021 (6950 2350);
PAINT SKYBLUE (6950 2350);
FORCEPROP 1 LAST VOLTAGE 16V
J 0
(6950 2450);
DISPLAY 0.617021 (6950 2450);
PAINT SKYBLUE (6950 2450);
FORCEPROP 1 LAST LOCATION PC284_P0_4
J 0
(6950 2550);
DISPLAY 0.617021 (6950 2550);
PAINT AQUA (6950 2550);
FORCEPROP 1 LASTPIN (6900 2500) $PN 1
J 0
(6910 2480);
DISPLAY 0.617021 (6910 2480);
PAINT MONO (6910 2480);
FORCEPROP 1 LASTPIN (6900 2300) $PN 2
J 0
(6910 2280);
DISPLAY 0.617021 (6910 2280);
PAINT MONO (6910 2280);
FORCEPROP 2 LAST CDS_LIB pure_quanta
J 0
(6900 2400);
DISPLAY INVISIBLE (6900 2400);
FORCEPROP 1 LAST PATH I43
J 0
(6950 2550);
DISPLAY 0.978723 (6950 2550);
PAINT WHITE (6950 2550);
DISPLAY INVISIBLE (6950 2550);
FORCEPROP 1 LAST LOCATION PC284_P0_4
J 0
(6950 2600);
DISPLAY 1.021277 (6950 2600);
PAINT AQUA (6950 2600);
DISPLAY INVISIBLE (6950 2600);
FORCEPROP 0 LAST $SEC 1
J 0
(6950 2600);
DISPLAY 0.680851 (6950 2600);
PAINT MONO (6950 2600);
DISPLAY INVISIBLE (6950 2600);
FORCEPROP 0 LAST CDS_SEC 1
J 0
(6950 2600);
DISPLAY 1.021277 (6950 2600);
DISPLAY INVISIBLE (6950 2600);
FORCEADD UNIVERSAL_GND..1
(7125 1975);
FORCEPROP 3 LASTPIN (7125 2025) SIG_NAME GND\g
J 0
(7135 2035);
DISPLAY 0.659574 (7135 2035);
PAINT MONO (7135 2035);
DISPLAY INVISIBLE (7135 2035);
FORCEPROP 2 LAST CDS_LIB logical_power
J 0
(7125 1975);
PAINT MONO (7125 1975);
DISPLAY INVISIBLE (7125 1975);
FORCEPROP 1 LAST HDL_POWER GND
J 1
(7150 1900);
DISPLAY 0.872340 (7150 1900);
PAINT GREEN (7150 1900);
DISPLAY INVISIBLE (7150 1900);
FORCEPROP 1 LAST PATH I44
J 0
(7200 1975);
DISPLAY 0.872340 (7200 1975);
PAINT AQUA (7200 1975);
DISPLAY INVISIBLE (7200 1975);
FORCEADD VCC15..1
(7125 2775);
FORCEPROP 3 LASTPIN (7125 2725) SIG_NAME SW_P12V_PVCCIN_CPU0_FLT\g
J 0
(7135 2735);
DISPLAY 0.659574 (7135 2735);
PAINT MONO (7135 2735);
DISPLAY INVISIBLE (7135 2735);
FORCEPROP 1 LAST HDL_POWER SW_P12V_PVCCIN_CPU0_FLT
J 1
(7175 2825);
DISPLAY 0.617021 (7175 2825);
PAINT GREEN (7175 2825);
FORCEPROP 2 LAST CDS_LIB logical_power
J 0
(7125 2775);
DISPLAY INVISIBLE (7125 2775);
FORCEPROP 1 LAST PATH I45
J 0
(7175 2800);
DISPLAY 0.872340 (7175 2800);
PAINT AQUA (7175 2800);
DISPLAY INVISIBLE (7175 2800);
FORCEADD Q_RES..1
(7100 3775);
FORCEPROP 1 LAST PART_NUMBER CS00002JB13
J 0
(6975 3825);
DISPLAY 0.617021 (6975 3825);
PAINT BLUE (6975 3825);
DISPLAY INVISIBLE (6975 3825);
FORCEPROP 1 LAST MATERIAL CHIP
J 0
(7375 3775);
DISPLAY 0.617021 (7375 3775);
PAINT SKYBLUE (7375 3775);
FORCEPROP 1 LAST VALUE 0
J 2
(7275 3775);
DISPLAY 0.617021 (7275 3775);
PAINT SKYBLUE (7275 3775);
FORCEPROP 1 LAST PACK_TYPE 0402LF
J 0
(6975 3875);
DISPLAY 0.617021 (6975 3875);
PAINT SKYBLUE (6975 3875);
FORCEPROP 1 LAST TOLERANCE 5%
J 0
(7300 3775);
DISPLAY 0.617021 (7300 3775);
PAINT SKYBLUE (7300 3775);
FORCEPROP 1 LAST WATTAGE 1/16W
J 2
(7350 3875);
DISPLAY 0.617021 (7350 3875);
PAINT SKYBLUE (7350 3875);
FORCEPROP 1 LAST LOCATION PR149
J 0
(6825 3775);
DISPLAY 0.617021 (6825 3775);
PAINT AQUA (6825 3775);
FORCEPROP 1 LASTPIN (7000 3775) $PN 1
J 0
(7012 3787);
DISPLAY 0.617021 (7012 3787);
PAINT MONO (7012 3787);
FORCEPROP 1 LASTPIN (7200 3775) $PN 2
J 0
(7162 3787);
DISPLAY 0.617021 (7162 3787);
PAINT MONO (7162 3787);
FORCEPROP 2 LAST CDS_LIB pure_quanta
J 0
(7100 3775);
DISPLAY INVISIBLE (7100 3775);
FORCEPROP 1 LAST PATH I46
J 0
(7050 3925);
DISPLAY 0.978723 (7050 3925);
PAINT WHITE (7050 3925);
DISPLAY INVISIBLE (7050 3925);
FORCEPROP 0 LAST $SEC 1
J 0
(7350 3925);
DISPLAY 0.680851 (7350 3925);
PAINT MONO (7350 3925);
DISPLAY INVISIBLE (7350 3925);
FORCEPROP 0 LAST CDS_SEC 1
J 0
(7350 3925);
DISPLAY 1.021277 (7350 3925);
DISPLAY INVISIBLE (7350 3925);
FORCEADD OFFPAGE..6
(5750 4075);
FORCEPROP 2 LAST $XR0 267 
J 0
(5470 4075);
DISPLAY 0.638298 (5470 4075);
PAINT MONO (5470 4075);
FORCEPROP 1 LAST COMMENT_BODY TRUE
J 0
(5850 4000);
DISPLAY 0.872340 (5850 4000);
PAINT GREEN (5850 4000);
DISPLAY INVISIBLE (5850 4000);
FORCEPROP 1 LAST OFFPAGE TRUE
J 0
(6075 3950);
DISPLAY 0.872340 (6075 3950);
PAINT GREEN (6075 3950);
DISPLAY INVISIBLE (6075 3950);
FORCEPROP 2 LAST CDS_LIB standard
J 0
(5750 4075);
DISPLAY INVISIBLE (5750 4075);
FORCEPROP 2 LAST PATH I47
J 0
(5475 4125);
DISPLAY 1.021277 (5475 4125);
DISPLAY INVISIBLE (5475 4125);
FORCEADD Q_CAP..1
(5350 5225);
FORCEPROP 1 LAST PART_NUMBER TMP_QCH2336K1B12
J 0
(5400 5075);
DISPLAY 0.617021 (5400 5075);
PAINT BLUE (5400 5075);
DISPLAY INVISIBLE (5400 5075);
FORCEPROP 1 LAST MATERIAL X7R
J 0
(5400 5175);
DISPLAY 0.617021 (5400 5175);
PAINT SKYBLUE (5400 5175);
FORCEPROP 1 LAST TOLERANCE 10%
J 0
(5400 5225);
DISPLAY 0.617021 (5400 5225);
PAINT SKYBLUE (5400 5225);
FORCEPROP 1 LAST VALUE 3300PF
J 0
(5400 5325);
DISPLAY 0.617021 (5400 5325);
PAINT SKYBLUE (5400 5325);
FORCEPROP 1 LAST VOLTAGE 50V
J 0
(5400 5275);
DISPLAY 0.617021 (5400 5275);
PAINT SKYBLUE (5400 5275);
FORCEPROP 1 LAST PACK_TYPE 0402
J 0
(5400 5125);
DISPLAY 0.617021 (5400 5125);
PAINT SKYBLUE (5400 5125);
FORCEPROP 1 LAST LOCATION PC275_P0_3
J 0
(5400 5375);
DISPLAY 0.617021 (5400 5375);
PAINT AQUA (5400 5375);
FORCEPROP 1 LASTPIN (5350 5325) $PN 1
J 0
(5360 5305);
DISPLAY 0.617021 (5360 5305);
PAINT MONO (5360 5305);
FORCEPROP 1 LASTPIN (5350 5125) $PN 2
J 0
(5360 5105);
DISPLAY 0.617021 (5360 5105);
PAINT MONO (5360 5105);
FORCEPROP 2 LAST CDS_LIB pure_quanta
J 0
(5350 5225);
DISPLAY INVISIBLE (5350 5225);
FORCEPROP 1 LAST PATH I48
J 0
(5400 5375);
DISPLAY 0.978723 (5400 5375);
PAINT WHITE (5400 5375);
DISPLAY INVISIBLE (5400 5375);
FORCEPROP 1 LAST LOCATION PC275_P0_3
J 0
(5400 5425);
DISPLAY 1.021277 (5400 5425);
PAINT AQUA (5400 5425);
DISPLAY INVISIBLE (5400 5425);
FORCEPROP 0 LAST $SEC 1
J 0
(5400 5425);
DISPLAY 0.680851 (5400 5425);
PAINT MONO (5400 5425);
DISPLAY INVISIBLE (5400 5425);
FORCEPROP 0 LAST CDS_SEC 1
J 0
(5400 5425);
DISPLAY 1.021277 (5400 5425);
DISPLAY INVISIBLE (5400 5425);
FORCEADD Q_RES..1
(5800 4775);
FORCEPROP 1 LAST PART_NUMBER CS-3302FB01
J 0
(5700 4825);
DISPLAY 0.617021 (5700 4825);
PAINT BLUE (5700 4825);
DISPLAY INVISIBLE (5700 4825);
FORCEPROP 1 LAST MATERIAL CHIP
J 0
(5700 4875);
DISPLAY 0.617021 (5700 4875);
PAINT SKYBLUE (5700 4875);
FORCEPROP 1 LAST PACK_TYPE 0402LF
J 0
(5700 4850);
DISPLAY 0.617021 (5700 4850);
PAINT SKYBLUE (5700 4850);
FORCEPROP 1 LAST WATTAGE 1/16W
J 2
(5925 4850);
DISPLAY 0.617021 (5925 4850);
PAINT SKYBLUE (5925 4850);
FORCEPROP 1 LAST VALUE 3.3
J 2
(6000 4775);
DISPLAY 0.617021 (6000 4775);
PAINT SKYBLUE (6000 4775);
FORCEPROP 1 LAST TOLERANCE 1%
J 0
(6025 4775);
DISPLAY 0.617021 (6025 4775);
PAINT SKYBLUE (6025 4775);
FORCEPROP 1 LAST LOCATION PR1769
J 0
(5550 4775);
DISPLAY 0.617021 (5550 4775);
PAINT AQUA (5550 4775);
FORCEPROP 1 LASTPIN (5700 4775) $PN 1
J 0
(5712 4787);
DISPLAY 0.617021 (5712 4787);
FORCEPROP 1 LASTPIN (5900 4775) $PN 2
J 0
(5862 4787);
DISPLAY 0.617021 (5862 4787);
FORCEPROP 2 LAST CDS_LIB pure_quanta
J 0
(5800 4775);
PAINT MONO (5800 4775);
DISPLAY INVISIBLE (5800 4775);
FORCEPROP 1 LAST PATH I49
J 0
(5750 4925);
DISPLAY 0.978723 (5750 4925);
PAINT WHITE (5750 4925);
DISPLAY INVISIBLE (5750 4925);
FORCEPROP 2 LAST $SEC 1
J 0
(5750 4975);
DISPLAY 0.680851 (5750 4975);
PAINT MONO (5750 4975);
DISPLAY INVISIBLE (5750 4975);
FORCEPROP 2 LAST CDS_SEC 1
J 0
(5750 4975);
DISPLAY 1.021277 (5750 4975);
DISPLAY INVISIBLE (5750 4975);
FORCEADD UNIVERSAL_GND..1
(2625 3600);
FORCEPROP 3 LASTPIN (2625 3650) SIG_NAME GND\g
J 0
(2635 3660);
DISPLAY 0.659574 (2635 3660);
PAINT MONO (2635 3660);
DISPLAY INVISIBLE (2635 3660);
FORCEPROP 2 LAST CDS_LIB logical_power
J 0
(2625 3600);
PAINT MONO (2625 3600);
DISPLAY INVISIBLE (2625 3600);
FORCEPROP 1 LAST HDL_POWER GND
J 1
(2650 3525);
DISPLAY 0.872340 (2650 3525);
PAINT GREEN (2650 3525);
DISPLAY INVISIBLE (2650 3525);
FORCEPROP 1 LAST PATH I5
J 0
(2700 3600);
DISPLAY 0.872340 (2700 3600);
PAINT AQUA (2700 3600);
DISPLAY INVISIBLE (2700 3600);
FORCEADD Q_INDUCTOR4P_14..1
(7000 4200);
FORCEPROP 1 LAST PART_NUMBER CV+15^0TZ04
J 0
(6775 4360);
DISPLAY 0.617021 (6775 4360);
PAINT BLUE (6775 4360);
DISPLAY INVISIBLE (6775 4360);
FORCEPROP 2 LAST PART_TYPE SMLF
J 0
(6775 4550);
DISPLAY 1.021277 (6775 4550);
FORCEPROP 1 LAST MATERIAL IND
J 0
(6775 4410);
DISPLAY 0.617021 (6775 4410);
PAINT SKYBLUE (6775 4410);
FORCEPROP 2 LAST VALUE 150NH
J 0
(6775 4500);
DISPLAY 0.617021 (6775 4500);
PAINT SKYBLUE (6775 4500);
FORCEPROP 1 LAST LOCATION PL112
J 0
(6775 4455);
DISPLAY 0.617021 (6775 4455);
PAINT AQUA (6775 4455);
FORCEPROP 2 LASTPIN (6600 4325) $PN 1
J 2
(6590 4335);
DISPLAY 0.617021 (6590 4335);
PAINT MONO (6590 4335);
FORCEPROP 2 LASTPIN (6600 4075) $PN 2
J 2
(6590 4085);
DISPLAY 0.617021 (6590 4085);
PAINT MONO (6590 4085);
FORCEPROP 2 LASTPIN (7400 4075) $PN 3
J 0
(7410 4085);
DISPLAY 0.617021 (7410 4085);
PAINT MONO (7410 4085);
FORCEPROP 2 LASTPIN (7400 4325) $PN 4
J 0
(7410 4335);
DISPLAY 0.617021 (7410 4335);
PAINT MONO (7410 4335);
FORCEPROP 2 LAST SEC_TYPE 
J 0
(6775 4600);
DISPLAY 1.021277 (6775 4600);
DISPLAY INVISIBLE (6775 4600);
FORCEPROP 2 LAST CDS_LIB pure_quanta
J 0
(7000 4200);
DISPLAY INVISIBLE (7000 4200);
FORCEPROP 1 LAST NEEDS_NO_SIZE TRUE
J 0
(7000 4200);
DISPLAY 0.468085 (7000 4200);
PAINT GREEN (7000 4200);
DISPLAY INVISIBLE (7000 4200);
FORCEPROP 1 LAST PATH I50
J 0
(7200 4355);
DISPLAY 0.723404 (7200 4355);
PAINT GREEN (7200 4355);
DISPLAY INVISIBLE (7200 4355);
FORCEPROP 2 LAST SEC 1
J 0
(6775 4600);
DISPLAY 0.680851 (6775 4600);
PAINT MONO (6775 4600);
DISPLAY INVISIBLE (6775 4600);
FORCEADD Q_CAP..1
R 2
(6525 4600);
FORCEPROP 1 LAST PART_NUMBER CH4106K1B01
J 2
(6475 4550);
DISPLAY 0.617021 (6475 4550);
PAINT BLUE (6475 4550);
DISPLAY INVISIBLE (6475 4550);
FORCEPROP 1 LAST TOLERANCE 10%
J 2
(6475 4600);
DISPLAY 0.617021 (6475 4600);
PAINT SKYBLUE (6475 4600);
FORCEPROP 1 LAST VALUE 100NF
J 2
(6475 4650);
DISPLAY 0.617021 (6475 4650);
PAINT SKYBLUE (6475 4650);
FORCEPROP 1 LAST VOLTAGE 50V
J 2
(6475 4625);
DISPLAY 0.617021 (6475 4625);
PAINT SKYBLUE (6475 4625);
FORCEPROP 1 LAST MATERIAL X7R
J 2
(6475 4575);
DISPLAY 0.617021 (6475 4575);
PAINT SKYBLUE (6475 4575);
FORCEPROP 1 LAST PACK_TYPE C0402
J 2
(6475 4525);
DISPLAY 0.617021 (6475 4525);
PAINT SKYBLUE (6475 4525);
FORCEPROP 1 LAST LOCATION PC279
J 2
(6475 4675);
DISPLAY 0.617021 (6475 4675);
PAINT AQUA (6475 4675);
FORCEPROP 1 LASTPIN (6525 4700) $PN 1
J 2
(6515 4680);
DISPLAY 0.617021 (6515 4680);
FORCEPROP 1 LASTPIN (6525 4500) $PN 2
J 2
(6515 4480);
DISPLAY 0.617021 (6515 4480);
FORCEPROP 2 LAST CDS_LIB pure_quanta
J 2
(6525 4600);
PAINT MONO (6525 4600);
DISPLAY INVISIBLE (6525 4600);
FORCEPROP 1 LAST PATH I51
J 2
(6475 4750);
DISPLAY 0.978723 (6475 4750);
PAINT WHITE (6475 4750);
DISPLAY INVISIBLE (6475 4750);
FORCEPROP 2 LAST $SEC 1
J 0
(6475 4800);
DISPLAY 0.680851 (6475 4800);
PAINT MONO (6475 4800);
DISPLAY INVISIBLE (6475 4800);
FORCEPROP 2 LAST CDS_SEC 1
J 0
(6475 4800);
DISPLAY 1.021277 (6475 4800);
DISPLAY INVISIBLE (6475 4800);
FORCEADD Q_CAP..1
(5750 5225);
FORCEPROP 1 LAST PART_NUMBER CH5103KEB01
J 0
(5800 5075);
DISPLAY 0.617021 (5800 5075);
PAINT BLUE (5800 5075);
DISPLAY INVISIBLE (5800 5075);
FORCEPROP 1 LAST MATERIAL X6S
J 0
(5800 5175);
DISPLAY 0.617021 (5800 5175);
PAINT SKYBLUE (5800 5175);
FORCEPROP 1 LAST TOLERANCE 10%
J 0
(5800 5225);
DISPLAY 0.617021 (5800 5225);
PAINT SKYBLUE (5800 5225);
FORCEPROP 1 LAST VALUE 1UF
J 0
(5800 5325);
DISPLAY 0.617021 (5800 5325);
PAINT SKYBLUE (5800 5325);
FORCEPROP 1 LAST VOLTAGE 16V
J 0
(5800 5275);
DISPLAY 0.617021 (5800 5275);
PAINT SKYBLUE (5800 5275);
FORCEPROP 1 LAST PACK_TYPE C0402
J 0
(5800 5125);
DISPLAY 0.617021 (5800 5125);
PAINT SKYBLUE (5800 5125);
FORCEPROP 1 LAST LOCATION PC277_P0_3
J 0
(5800 5375);
DISPLAY 0.617021 (5800 5375);
PAINT AQUA (5800 5375);
FORCEPROP 1 LASTPIN (5750 5325) $PN 1
J 0
(5760 5305);
DISPLAY 0.617021 (5760 5305);
PAINT MONO (5760 5305);
FORCEPROP 1 LASTPIN (5750 5125) $PN 2
J 0
(5760 5105);
DISPLAY 0.617021 (5760 5105);
PAINT MONO (5760 5105);
FORCEPROP 2 LAST CDS_LIB pure_quanta
J 0
(5750 5225);
DISPLAY INVISIBLE (5750 5225);
FORCEPROP 1 LAST PATH I52
J 0
(5800 5375);
DISPLAY 0.978723 (5800 5375);
PAINT WHITE (5800 5375);
DISPLAY INVISIBLE (5800 5375);
FORCEPROP 1 LAST LOCATION PC277_P0_3
J 0
(5800 5425);
DISPLAY 1.021277 (5800 5425);
PAINT AQUA (5800 5425);
DISPLAY INVISIBLE (5800 5425);
FORCEPROP 0 LAST $SEC 1
J 0
(5800 5425);
DISPLAY 0.680851 (5800 5425);
PAINT MONO (5800 5425);
DISPLAY INVISIBLE (5800 5425);
FORCEPROP 0 LAST CDS_SEC 1
J 0
(5800 5425);
DISPLAY 1.021277 (5800 5425);
DISPLAY INVISIBLE (5800 5425);
FORCEADD Q_CAP..1
(6150 5225);
FORCEPROP 1 LAST PART_NUMBER CH6223MEA01
J 0
(6200 5075);
DISPLAY 0.617021 (6200 5075);
PAINT BLUE (6200 5075);
DISPLAY INVISIBLE (6200 5075);
FORCEPROP 1 LAST MATERIAL X6S
J 0
(6200 5175);
DISPLAY 0.617021 (6200 5175);
PAINT SKYBLUE (6200 5175);
FORCEPROP 1 LAST TOLERANCE 20%
J 0
(6200 5225);
DISPLAY 0.617021 (6200 5225);
PAINT SKYBLUE (6200 5225);
FORCEPROP 1 LAST VALUE 22UF
J 0
(6200 5325);
DISPLAY 0.617021 (6200 5325);
PAINT SKYBLUE (6200 5325);
FORCEPROP 1 LAST VOLTAGE 16V
J 0
(6200 5275);
DISPLAY 0.617021 (6200 5275);
PAINT SKYBLUE (6200 5275);
FORCEPROP 1 LAST PACK_TYPE C0805
J 0
(6200 5125);
DISPLAY 0.617021 (6200 5125);
PAINT SKYBLUE (6200 5125);
FORCEPROP 1 LAST LOCATION PC281_P0_3
J 0
(6200 5375);
DISPLAY 0.617021 (6200 5375);
PAINT AQUA (6200 5375);
FORCEPROP 1 LASTPIN (6150 5325) $PN 1
J 0
(6160 5305);
DISPLAY 0.617021 (6160 5305);
PAINT MONO (6160 5305);
FORCEPROP 1 LASTPIN (6150 5125) $PN 2
J 0
(6160 5105);
DISPLAY 0.617021 (6160 5105);
PAINT MONO (6160 5105);
FORCEPROP 2 LAST CDS_LIB pure_quanta
J 0
(6150 5225);
DISPLAY INVISIBLE (6150 5225);
FORCEPROP 1 LAST PATH I53
J 0
(6200 5375);
DISPLAY 0.978723 (6200 5375);
PAINT WHITE (6200 5375);
DISPLAY INVISIBLE (6200 5375);
FORCEPROP 1 LAST LOCATION PC281_P0_3
J 0
(6200 5425);
DISPLAY 1.021277 (6200 5425);
PAINT AQUA (6200 5425);
DISPLAY INVISIBLE (6200 5425);
FORCEPROP 0 LAST $SEC 1
J 0
(6200 5425);
DISPLAY 0.680851 (6200 5425);
PAINT MONO (6200 5425);
DISPLAY INVISIBLE (6200 5425);
FORCEPROP 0 LAST CDS_SEC 1
J 0
(6200 5425);
DISPLAY 1.021277 (6200 5425);
DISPLAY INVISIBLE (6200 5425);
FORCEADD Q_CAP..1
(6550 5225);
FORCEPROP 1 LAST PART_NUMBER CH6223MEA01
J 0
(6600 5075);
DISPLAY 0.617021 (6600 5075);
PAINT BLUE (6600 5075);
DISPLAY INVISIBLE (6600 5075);
FORCEPROP 1 LAST MATERIAL X6S
J 0
(6600 5175);
DISPLAY 0.617021 (6600 5175);
PAINT SKYBLUE (6600 5175);
FORCEPROP 1 LAST TOLERANCE 20%
J 0
(6600 5225);
DISPLAY 0.617021 (6600 5225);
PAINT SKYBLUE (6600 5225);
FORCEPROP 1 LAST VALUE 22UF
J 0
(6600 5325);
DISPLAY 0.617021 (6600 5325);
PAINT SKYBLUE (6600 5325);
FORCEPROP 1 LAST VOLTAGE 16V
J 0
(6600 5275);
DISPLAY 0.617021 (6600 5275);
PAINT SKYBLUE (6600 5275);
FORCEPROP 1 LAST PACK_TYPE C0805
J 0
(6600 5125);
DISPLAY 0.617021 (6600 5125);
PAINT SKYBLUE (6600 5125);
FORCEPROP 1 LAST LOCATION PC283_P0_3
J 0
(6600 5375);
DISPLAY 0.617021 (6600 5375);
PAINT AQUA (6600 5375);
FORCEPROP 1 LASTPIN (6550 5325) $PN 1
J 0
(6560 5305);
DISPLAY 0.617021 (6560 5305);
PAINT MONO (6560 5305);
FORCEPROP 1 LASTPIN (6550 5125) $PN 2
J 0
(6560 5105);
DISPLAY 0.617021 (6560 5105);
PAINT MONO (6560 5105);
FORCEPROP 2 LAST CDS_LIB pure_quanta
J 0
(6550 5225);
DISPLAY INVISIBLE (6550 5225);
FORCEPROP 1 LAST PATH I54
J 0
(6600 5375);
DISPLAY 0.978723 (6600 5375);
PAINT WHITE (6600 5375);
DISPLAY INVISIBLE (6600 5375);
FORCEPROP 1 LAST LOCATION PC283_P0_3
J 0
(6600 5425);
DISPLAY 1.021277 (6600 5425);
PAINT AQUA (6600 5425);
DISPLAY INVISIBLE (6600 5425);
FORCEPROP 0 LAST $SEC 1
J 0
(6600 5425);
DISPLAY 0.680851 (6600 5425);
PAINT MONO (6600 5425);
DISPLAY INVISIBLE (6600 5425);
FORCEPROP 0 LAST CDS_SEC 1
J 0
(6600 5425);
DISPLAY 1.021277 (6600 5425);
DISPLAY INVISIBLE (6600 5425);
FORCEADD UNIVERSAL_GND..1
(7150 4800);
FORCEPROP 3 LASTPIN (7150 4850) SIG_NAME GND\g
J 0
(7160 4860);
DISPLAY 0.659574 (7160 4860);
PAINT MONO (7160 4860);
DISPLAY INVISIBLE (7160 4860);
FORCEPROP 2 LAST CDS_LIB logical_power
J 0
(7150 4800);
PAINT MONO (7150 4800);
DISPLAY INVISIBLE (7150 4800);
FORCEPROP 1 LAST HDL_POWER GND
J 1
(7175 4725);
DISPLAY 0.872340 (7175 4725);
PAINT GREEN (7175 4725);
DISPLAY INVISIBLE (7175 4725);
FORCEPROP 1 LAST PATH I55
J 0
(7225 4800);
DISPLAY 0.872340 (7225 4800);
PAINT AQUA (7225 4800);
DISPLAY INVISIBLE (7225 4800);
FORCEADD Q_CAP..1
(6925 5225);
FORCEPROP 1 LAST PART_NUMBER CH6223MEA01
J 0
(6975 5075);
DISPLAY 0.617021 (6975 5075);
PAINT BLUE (6975 5075);
DISPLAY INVISIBLE (6975 5075);
FORCEPROP 1 LAST MATERIAL X6S
J 0
(6975 5175);
DISPLAY 0.617021 (6975 5175);
PAINT SKYBLUE (6975 5175);
FORCEPROP 1 LAST TOLERANCE 20%
J 0
(6975 5225);
DISPLAY 0.617021 (6975 5225);
PAINT SKYBLUE (6975 5225);
FORCEPROP 1 LAST VALUE 22UF
J 0
(6975 5325);
DISPLAY 0.617021 (6975 5325);
PAINT SKYBLUE (6975 5325);
FORCEPROP 1 LAST VOLTAGE 16V
J 0
(6975 5275);
DISPLAY 0.617021 (6975 5275);
PAINT SKYBLUE (6975 5275);
FORCEPROP 1 LAST PACK_TYPE C0805
J 0
(6975 5125);
DISPLAY 0.617021 (6975 5125);
PAINT SKYBLUE (6975 5125);
FORCEPROP 1 LAST LOCATION PC285_P0_3
J 0
(6975 5375);
DISPLAY 0.617021 (6975 5375);
PAINT AQUA (6975 5375);
FORCEPROP 1 LASTPIN (6925 5325) $PN 1
J 0
(6935 5305);
DISPLAY 0.617021 (6935 5305);
PAINT MONO (6935 5305);
FORCEPROP 1 LASTPIN (6925 5125) $PN 2
J 0
(6935 5105);
DISPLAY 0.617021 (6935 5105);
PAINT MONO (6935 5105);
FORCEPROP 2 LAST CDS_LIB pure_quanta
J 0
(6925 5225);
DISPLAY INVISIBLE (6925 5225);
FORCEPROP 1 LAST PATH I56
J 0
(6975 5375);
DISPLAY 0.978723 (6975 5375);
PAINT WHITE (6975 5375);
DISPLAY INVISIBLE (6975 5375);
FORCEPROP 1 LAST LOCATION PC285_P0_3
J 0
(6975 5425);
DISPLAY 1.021277 (6975 5425);
PAINT AQUA (6975 5425);
DISPLAY INVISIBLE (6975 5425);
FORCEPROP 0 LAST $SEC 1
J 0
(6975 5425);
DISPLAY 0.680851 (6975 5425);
PAINT MONO (6975 5425);
DISPLAY INVISIBLE (6975 5425);
FORCEPROP 0 LAST CDS_SEC 1
J 0
(6975 5425);
DISPLAY 1.021277 (6975 5425);
DISPLAY INVISIBLE (6975 5425);
FORCEADD VCC15..1
(7150 5600);
FORCEPROP 3 LASTPIN (7150 5550) SIG_NAME SW_P12V_PVCCIN_CPU0_FLT\g
J 0
(7160 5560);
DISPLAY 0.659574 (7160 5560);
PAINT MONO (7160 5560);
DISPLAY INVISIBLE (7160 5560);
FORCEPROP 1 LAST HDL_POWER SW_P12V_PVCCIN_CPU0_FLT
J 1
(7200 5650);
DISPLAY 0.617021 (7200 5650);
PAINT GREEN (7200 5650);
FORCEPROP 2 LAST CDS_LIB logical_power
J 0
(7150 5600);
DISPLAY INVISIBLE (7150 5600);
FORCEPROP 1 LAST PATH I57
J 0
(7200 5625);
DISPLAY 0.872340 (7200 5625);
PAINT AQUA (7200 5625);
DISPLAY INVISIBLE (7200 5625);
FORCEADD OFFPAGE..3
(7975 4075);
FORCEPROP 2 LAST $XR0 268 
J 0
(8189 4075);
DISPLAY 0.638298 (8189 4075);
PAINT MONO (8189 4075);
FORCEPROP 2 LAST CDS_LIB standard
J 0
(7975 4075);
DISPLAY INVISIBLE (7975 4075);
FORCEPROP 1 LAST OFFPAGE TRUE
J 0
(8300 3950);
DISPLAY 0.872340 (8300 3950);
PAINT GREEN (8300 3950);
DISPLAY INVISIBLE (8300 3950);
FORCEPROP 1 LAST COMMENT_BODY TRUE
J 0
(7925 3975);
DISPLAY 0.872340 (7925 3975);
PAINT GREEN (7925 3975);
DISPLAY INVISIBLE (7925 3975);
FORCEPROP 2 LAST PATH I58
J 0
(8200 4125);
DISPLAY 1.021277 (8200 4125);
DISPLAY INVISIBLE (8200 4125);
FORCEADD Q_CAP..1
(8750 4125);
FORCEPROP 1 LAST PART_NUMBER CH622KMEA03
J 0
(8800 3950);
DISPLAY 0.617021 (8800 3950);
PAINT BLUE (8800 3950);
DISPLAY INVISIBLE (8800 3950);
FORCEPROP 1 LAST PACK_TYPE C0805
J 0
(8800 4000);
DISPLAY 0.617021 (8800 4000);
PAINT SKYBLUE (8800 4000);
FORCEPROP 1 LAST VOLTAGE 4V
J 0
(8800 4150);
DISPLAY 0.617021 (8800 4150);
PAINT SKYBLUE (8800 4150);
FORCEPROP 1 LAST VALUE 22UF
J 0
(8800 4200);
DISPLAY 0.617021 (8800 4200);
PAINT SKYBLUE (8800 4200);
FORCEPROP 1 LAST TOLERANCE 20%
J 0
(8800 4100);
DISPLAY 0.617021 (8800 4100);
PAINT SKYBLUE (8800 4100);
FORCEPROP 1 LAST MATERIAL X6S
J 0
(8800 4050);
DISPLAY 0.617021 (8800 4050);
PAINT SKYBLUE (8800 4050);
FORCEPROP 1 LAST LOCATION PC289_P0_3
J 0
(8800 4250);
DISPLAY 0.617021 (8800 4250);
PAINT AQUA (8800 4250);
FORCEPROP 1 LASTPIN (8750 4225) $PN 1
J 0
(8760 4205);
DISPLAY 0.617021 (8760 4205);
PAINT MONO (8760 4205);
FORCEPROP 1 LASTPIN (8750 4025) $PN 2
J 0
(8760 4005);
DISPLAY 0.617021 (8760 4005);
PAINT MONO (8760 4005);
FORCEPROP 2 LAST CDS_LIB pure_quanta
J 0
(8750 4125);
DISPLAY INVISIBLE (8750 4125);
FORCEPROP 1 LAST PATH I59
J 0
(8800 4275);
DISPLAY 0.978723 (8800 4275);
PAINT WHITE (8800 4275);
DISPLAY INVISIBLE (8800 4275);
FORCEPROP 1 LAST LOCATION PC289_P0_3
J 0
(8800 4300);
DISPLAY 1.021277 (8800 4300);
PAINT AQUA (8800 4300);
DISPLAY INVISIBLE (8800 4300);
FORCEPROP 0 LAST $SEC 1
J 0
(8800 4300);
DISPLAY 0.680851 (8800 4300);
PAINT MONO (8800 4300);
DISPLAY INVISIBLE (8800 4300);
FORCEPROP 0 LAST CDS_SEC 1
J 0
(8800 4300);
DISPLAY 1.021277 (8800 4300);
DISPLAY INVISIBLE (8800 4300);
FORCEADD OFFPAGE..1
(3075 900);
FORCEPROP 2 LAST $XR0 266 
J 0
(2823 900);
DISPLAY 0.638298 (2823 900);
PAINT MONO (2823 900);
FORCEPROP 2 LAST CDS_LIB standard
J 0
(3075 900);
DISPLAY INVISIBLE (3075 900);
FORCEPROP 1 LAST OFFPAGE TRUE
J 0
(3400 775);
DISPLAY 0.872340 (3400 775);
PAINT GREEN (3400 775);
DISPLAY INVISIBLE (3400 775);
FORCEPROP 1 LAST COMMENT_BODY TRUE
J 0
(3200 800);
DISPLAY 0.872340 (3200 800);
PAINT GREEN (3200 800);
DISPLAY INVISIBLE (3200 800);
FORCEPROP 2 LAST PATH I6
J 0
(2825 950);
DISPLAY 1.021277 (2825 950);
DISPLAY INVISIBLE (2825 950);
FORCEADD Q_CAP..1
(8775 1300);
FORCEPROP 1 LAST PART_NUMBER CH622KMEA03
J 0
(8825 1125);
DISPLAY 0.617021 (8825 1125);
PAINT BLUE (8825 1125);
DISPLAY INVISIBLE (8825 1125);
FORCEPROP 1 LAST PACK_TYPE C0805
J 0
(8825 1175);
DISPLAY 0.617021 (8825 1175);
PAINT SKYBLUE (8825 1175);
FORCEPROP 1 LAST VOLTAGE 4V
J 0
(8825 1325);
DISPLAY 0.617021 (8825 1325);
PAINT SKYBLUE (8825 1325);
FORCEPROP 1 LAST VALUE 22UF
J 0
(8825 1375);
DISPLAY 0.617021 (8825 1375);
PAINT SKYBLUE (8825 1375);
FORCEPROP 1 LAST TOLERANCE 20%
J 0
(8825 1275);
DISPLAY 0.617021 (8825 1275);
PAINT SKYBLUE (8825 1275);
FORCEPROP 1 LAST MATERIAL X6S
J 0
(8825 1225);
DISPLAY 0.617021 (8825 1225);
PAINT SKYBLUE (8825 1225);
FORCEPROP 1 LAST LOCATION PC288_P0_4
J 0
(8825 1425);
DISPLAY 0.617021 (8825 1425);
PAINT AQUA (8825 1425);
FORCEPROP 1 LASTPIN (8775 1400) $PN 1
J 0
(8785 1380);
DISPLAY 0.617021 (8785 1380);
PAINT MONO (8785 1380);
FORCEPROP 1 LASTPIN (8775 1200) $PN 2
J 0
(8785 1180);
DISPLAY 0.617021 (8785 1180);
PAINT MONO (8785 1180);
FORCEPROP 2 LAST CDS_LIB pure_quanta
J 0
(8775 1300);
DISPLAY INVISIBLE (8775 1300);
FORCEPROP 1 LAST PATH I60
J 0
(8825 1450);
DISPLAY 0.978723 (8825 1450);
PAINT WHITE (8825 1450);
DISPLAY INVISIBLE (8825 1450);
FORCEPROP 1 LAST LOCATION PC288_P0_4
J 0
(8825 1475);
DISPLAY 1.021277 (8825 1475);
PAINT AQUA (8825 1475);
DISPLAY INVISIBLE (8825 1475);
FORCEPROP 0 LAST $SEC 1
J 0
(8825 1475);
DISPLAY 0.680851 (8825 1475);
PAINT MONO (8825 1475);
DISPLAY INVISIBLE (8825 1475);
FORCEPROP 0 LAST CDS_SEC 1
J 0
(8825 1475);
DISPLAY 1.021277 (8825 1475);
DISPLAY INVISIBLE (8825 1475);
FORCEADD Q_CAP..1
(9200 1300);
FORCEPROP 1 LAST PART_NUMBER CH622KMEA03
J 0
(9250 1125);
DISPLAY 0.617021 (9250 1125);
PAINT BLUE (9250 1125);
DISPLAY INVISIBLE (9250 1125);
FORCEPROP 1 LAST PACK_TYPE C0805
J 0
(9250 1175);
DISPLAY 0.617021 (9250 1175);
PAINT SKYBLUE (9250 1175);
FORCEPROP 1 LAST VOLTAGE 4V
J 0
(9250 1325);
DISPLAY 0.617021 (9250 1325);
PAINT SKYBLUE (9250 1325);
FORCEPROP 1 LAST VALUE 22UF
J 0
(9250 1375);
DISPLAY 0.617021 (9250 1375);
PAINT SKYBLUE (9250 1375);
FORCEPROP 1 LAST TOLERANCE 20%
J 0
(9250 1275);
DISPLAY 0.617021 (9250 1275);
PAINT SKYBLUE (9250 1275);
FORCEPROP 1 LAST MATERIAL X6S
J 0
(9250 1225);
DISPLAY 0.617021 (9250 1225);
PAINT SKYBLUE (9250 1225);
FORCEPROP 1 LAST LOCATION PC290_P0_4
J 0
(9250 1425);
DISPLAY 0.617021 (9250 1425);
PAINT AQUA (9250 1425);
FORCEPROP 1 LASTPIN (9200 1400) $PN 1
J 0
(9210 1380);
DISPLAY 0.617021 (9210 1380);
PAINT MONO (9210 1380);
FORCEPROP 1 LASTPIN (9200 1200) $PN 2
J 0
(9210 1180);
DISPLAY 0.617021 (9210 1180);
PAINT MONO (9210 1180);
FORCEPROP 2 LAST CDS_LIB pure_quanta
J 0
(9200 1300);
DISPLAY INVISIBLE (9200 1300);
FORCEPROP 1 LAST PATH I61
J 0
(9250 1450);
DISPLAY 0.978723 (9250 1450);
PAINT WHITE (9250 1450);
DISPLAY INVISIBLE (9250 1450);
FORCEPROP 1 LAST LOCATION PC290_P0_4
J 0
(9250 1475);
DISPLAY 1.021277 (9250 1475);
PAINT AQUA (9250 1475);
DISPLAY INVISIBLE (9250 1475);
FORCEPROP 0 LAST $SEC 1
J 0
(9250 1475);
DISPLAY 0.680851 (9250 1475);
PAINT MONO (9250 1475);
DISPLAY INVISIBLE (9250 1475);
FORCEPROP 0 LAST CDS_SEC 1
J 0
(9250 1475);
DISPLAY 1.021277 (9250 1475);
DISPLAY INVISIBLE (9250 1475);
FORCEADD UNIVERSAL_GND..1
(9500 925);
FORCEPROP 3 LASTPIN (9500 975) SIG_NAME GND\g
J 0
(9510 985);
DISPLAY 0.659574 (9510 985);
PAINT MONO (9510 985);
DISPLAY INVISIBLE (9510 985);
FORCEPROP 2 LAST CDS_LIB logical_power
J 0
(9500 925);
PAINT MONO (9500 925);
DISPLAY INVISIBLE (9500 925);
FORCEPROP 1 LAST HDL_POWER GND
J 1
(9525 850);
DISPLAY 0.872340 (9525 850);
PAINT GREEN (9525 850);
DISPLAY INVISIBLE (9525 850);
FORCEPROP 1 LAST PATH I62
J 0
(9575 925);
DISPLAY 0.872340 (9575 925);
PAINT AQUA (9575 925);
DISPLAY INVISIBLE (9575 925);
FORCEADD VCC15..1
(9500 1700);
FORCEPROP 3 LASTPIN (9500 1650) SIG_NAME PVCCIN_CPU0\g
J 0
(9510 1660);
DISPLAY 0.659574 (9510 1660);
PAINT MONO (9510 1660);
DISPLAY INVISIBLE (9510 1660);
FORCEPROP 1 LAST HDL_POWER PVCCIN_CPU0
J 1
(9500 1750);
DISPLAY 0.617021 (9500 1750);
PAINT GREEN (9500 1750);
FORCEPROP 2 LAST CDS_LIB logical_power
J 0
(9500 1700);
DISPLAY INVISIBLE (9500 1700);
FORCEPROP 1 LAST PATH I63
J 0
(9550 1725);
DISPLAY 0.872340 (9550 1725);
PAINT AQUA (9550 1725);
DISPLAY INVISIBLE (9550 1725);
FORCEADD UNIVERSAL_GND..1
(9475 3750);
FORCEPROP 3 LASTPIN (9475 3800) SIG_NAME GND\g
J 0
(9485 3810);
DISPLAY 0.659574 (9485 3810);
PAINT MONO (9485 3810);
DISPLAY INVISIBLE (9485 3810);
FORCEPROP 2 LAST CDS_LIB logical_power
J 0
(9475 3750);
PAINT MONO (9475 3750);
DISPLAY INVISIBLE (9475 3750);
FORCEPROP 1 LAST HDL_POWER GND
J 1
(9500 3675);
DISPLAY 0.872340 (9500 3675);
PAINT GREEN (9500 3675);
DISPLAY INVISIBLE (9500 3675);
FORCEPROP 1 LAST PATH I64
J 0
(9550 3750);
DISPLAY 0.872340 (9550 3750);
PAINT AQUA (9550 3750);
DISPLAY INVISIBLE (9550 3750);
FORCEADD Q_CAP..1
(9175 4125);
FORCEPROP 1 LAST PART_NUMBER CH622KMEA03
J 0
(9225 3950);
DISPLAY 0.617021 (9225 3950);
PAINT BLUE (9225 3950);
DISPLAY INVISIBLE (9225 3950);
FORCEPROP 1 LAST PACK_TYPE C0805
J 0
(9225 4000);
DISPLAY 0.617021 (9225 4000);
PAINT SKYBLUE (9225 4000);
FORCEPROP 1 LAST VOLTAGE 4V
J 0
(9225 4150);
DISPLAY 0.617021 (9225 4150);
PAINT SKYBLUE (9225 4150);
FORCEPROP 1 LAST VALUE 22UF
J 0
(9225 4200);
DISPLAY 0.617021 (9225 4200);
PAINT SKYBLUE (9225 4200);
FORCEPROP 1 LAST TOLERANCE 20%
J 0
(9225 4100);
DISPLAY 0.617021 (9225 4100);
PAINT SKYBLUE (9225 4100);
FORCEPROP 1 LAST MATERIAL X6S
J 0
(9225 4050);
DISPLAY 0.617021 (9225 4050);
PAINT SKYBLUE (9225 4050);
FORCEPROP 1 LAST LOCATION PC291_P0_3
J 0
(9225 4250);
DISPLAY 0.617021 (9225 4250);
PAINT AQUA (9225 4250);
FORCEPROP 1 LASTPIN (9175 4225) $PN 1
J 0
(9185 4205);
DISPLAY 0.617021 (9185 4205);
PAINT MONO (9185 4205);
FORCEPROP 1 LASTPIN (9175 4025) $PN 2
J 0
(9185 4005);
DISPLAY 0.617021 (9185 4005);
PAINT MONO (9185 4005);
FORCEPROP 2 LAST CDS_LIB pure_quanta
J 0
(9175 4125);
DISPLAY INVISIBLE (9175 4125);
FORCEPROP 1 LAST PATH I65
J 0
(9225 4275);
DISPLAY 0.978723 (9225 4275);
PAINT WHITE (9225 4275);
DISPLAY INVISIBLE (9225 4275);
FORCEPROP 1 LAST LOCATION PC291_P0_3
J 0
(9225 4300);
DISPLAY 1.021277 (9225 4300);
PAINT AQUA (9225 4300);
DISPLAY INVISIBLE (9225 4300);
FORCEPROP 0 LAST $SEC 1
J 0
(9225 4300);
DISPLAY 0.680851 (9225 4300);
PAINT MONO (9225 4300);
DISPLAY INVISIBLE (9225 4300);
FORCEPROP 0 LAST CDS_SEC 1
J 0
(9225 4300);
DISPLAY 1.021277 (9225 4300);
DISPLAY INVISIBLE (9225 4300);
FORCEADD VCC15..1
(9475 4525);
FORCEPROP 3 LASTPIN (9475 4475) SIG_NAME PVCCIN_CPU0\g
J 0
(9485 4485);
DISPLAY 0.659574 (9485 4485);
PAINT MONO (9485 4485);
DISPLAY INVISIBLE (9485 4485);
FORCEPROP 1 LAST HDL_POWER PVCCIN_CPU0
J 1
(9475 4575);
DISPLAY 0.617021 (9475 4575);
PAINT GREEN (9475 4575);
FORCEPROP 2 LAST CDS_LIB logical_power
J 0
(9475 4525);
DISPLAY INVISIBLE (9475 4525);
FORCEPROP 1 LAST PATH I66
J 0
(9525 4550);
DISPLAY 0.872340 (9525 4550);
PAINT AQUA (9525 4550);
DISPLAY INVISIBLE (9525 4550);
FORCEADD OFFPAGE..5
(3075 1000);
FORCEPROP 2 LAST $XR4 266 
J 0
(2790 1108);
DISPLAY 0.638298 (2790 1108);
PAINT MONO (2790 1108);
FORCEPROP 2 LAST $XR3 270 
J 0
(2790 1072);
DISPLAY 0.638298 (2790 1072);
PAINT MONO (2790 1072);
FORCEPROP 2 LAST $XR2 269 
J 0
(2790 1036);
DISPLAY 0.638298 (2790 1036);
PAINT MONO (2790 1036);
FORCEPROP 2 LAST $XR1 268 
J 0
(2790 964);
DISPLAY 0.638298 (2790 964);
PAINT MONO (2790 964);
FORCEPROP 2 LAST $XR0 267 
J 0
(2790 1000);
DISPLAY 0.638298 (2790 1000);
PAINT MONO (2790 1000);
FORCEPROP 2 LAST CDS_LIB standard
J 0
(3075 1000);
DISPLAY INVISIBLE (3075 1000);
FORCEPROP 1 LAST OFFPAGE TRUE
J 0
(3400 875);
DISPLAY 0.872340 (3400 875);
PAINT GREEN (3400 875);
DISPLAY INVISIBLE (3400 875);
FORCEPROP 1 LAST COMMENT_BODY TRUE
J 0
(3175 925);
DISPLAY 0.872340 (3175 925);
PAINT GREEN (3175 925);
DISPLAY INVISIBLE (3175 925);
FORCEPROP 2 LAST PATH I7
J 0
(2800 1150);
DISPLAY 1.021277 (2800 1150);
DISPLAY INVISIBLE (2800 1150);
FORCEADD OFFPAGE..1
(3075 1400);
FORCEPROP 2 LAST $XR6 272 
J 0
(2103 1400);
DISPLAY 0.638298 (2103 1400);
PAINT MONO (2103 1400);
FORCEPROP 2 LAST $XR5 271 
J 0
(2223 1400);
DISPLAY 0.638298 (2223 1400);
PAINT MONO (2223 1400);
FORCEPROP 2 LAST $XR4 270 
J 0
(2343 1400);
DISPLAY 0.638298 (2343 1400);
PAINT MONO (2343 1400);
FORCEPROP 2 LAST $XR3 269 
J 0
(2463 1400);
DISPLAY 0.638298 (2463 1400);
PAINT MONO (2463 1400);
FORCEPROP 2 LAST $XR2 268 
J 0
(2583 1400);
DISPLAY 0.638298 (2583 1400);
PAINT MONO (2583 1400);
FORCEPROP 2 LAST $XR1 267 
J 0
(2703 1400);
DISPLAY 0.638298 (2703 1400);
PAINT MONO (2703 1400);
FORCEPROP 2 LAST $XR0 266 
J 0
(2823 1400);
DISPLAY 0.638298 (2823 1400);
PAINT MONO (2823 1400);
FORCEPROP 2 LAST CDS_LIB standard
J 0
(3075 1400);
DISPLAY INVISIBLE (3075 1400);
FORCEPROP 1 LAST OFFPAGE TRUE
J 0
(3400 1275);
DISPLAY 0.872340 (3400 1275);
PAINT GREEN (3400 1275);
DISPLAY INVISIBLE (3400 1275);
FORCEPROP 1 LAST COMMENT_BODY TRUE
J 0
(3200 1300);
DISPLAY 0.872340 (3200 1300);
PAINT GREEN (3200 1300);
DISPLAY INVISIBLE (3200 1300);
FORCEPROP 2 LAST PATH I8
J 0
(2825 1450);
DISPLAY 1.021277 (2825 1450);
DISPLAY INVISIBLE (2825 1450);
FORCEADD OFFPAGE..5
(3075 1500);
FORCEPROP 2 LAST $XR0 266 
J 0
(2790 1500);
DISPLAY 0.638298 (2790 1500);
PAINT MONO (2790 1500);
FORCEPROP 2 LAST CDS_LIB standard
J 0
(3075 1500);
DISPLAY INVISIBLE (3075 1500);
FORCEPROP 1 LAST OFFPAGE TRUE
J 0
(3400 1375);
DISPLAY 0.872340 (3400 1375);
PAINT GREEN (3400 1375);
DISPLAY INVISIBLE (3400 1375);
FORCEPROP 1 LAST COMMENT_BODY TRUE
J 0
(3175 1425);
DISPLAY 0.872340 (3175 1425);
PAINT GREEN (3175 1425);
DISPLAY INVISIBLE (3175 1425);
FORCEPROP 2 LAST PATH I9
J 0
(2800 1550);
DISPLAY 1.021277 (2800 1550);
DISPLAY INVISIBLE (2800 1550);
FORCEADD DNS..1
(2600 975);
PAINT RED (2600 975);
FORCEPROP 2 LAST CDS_LIB mstr_misc
J 0
(2600 975);
PAINT MONO (2600 975);
DISPLAY INVISIBLE (2600 975);
FORCEPROP 1 LAST COMMENT_BODY TRUE
R 1
J 0
(2675 750);
DISPLAY 0.872340 (2675 750);
PAINT GREEN (2675 750);
DISPLAY INVISIBLE (2675 750);
FORCEADD DNS..1
(2625 3800);
PAINT RED (2625 3800);
FORCEPROP 2 LAST CDS_LIB mstr_misc
J 0
(2625 3800);
PAINT MONO (2625 3800);
DISPLAY INVISIBLE (2625 3800);
FORCEPROP 1 LAST COMMENT_BODY TRUE
R 1
J 0
(2700 3575);
DISPLAY 0.872340 (2700 3575);
PAINT GREEN (2700 3575);
DISPLAY INVISIBLE (2700 3575);
FORCEADD QUANTA_TITLE_BLOCK_C..1
(10025 -100);
FORCEPROP 0 LAST CDS_CON_LAST_MODIFIED Fri Aug 25 14:04:38 2023
J 0
(8140 -85);
DISPLAY INVISIBLE (8140 -85);
FORCEPROP 1 LAST CUSTOM_TXT_CDS <CON_LAST_MODIFIED>
J 0
(8140 -85);
DISPLAY 0.978723 (8140 -85);
FORCEPROP 2 LAST CUSTOM_TXT_CDS <XR_PAGE_TITLE>
J 0
(2135 5150);
DISPLAY 0.638298 (2135 5150);
PAINT PINK (2135 5150);
DISPLAY INVISIBLE (2135 5150);
FORCEPROP 1 LAST CUSTOM_TXT_CDS <NAME_2>
J 0
(6850 -50);
FORCEPROP 1 LAST CUSTOM_TXT_CDS <NAME_1>
J 0
(6850 75);
FORCEPROP 1 LAST CUSTOM_TXT_CDS <Q_NUMBER>
J 0
(8622 3);
DISPLAY 1.212766 (8622 3);
FORCEPROP 1 LAST CUSTOM_TXT_CDS <Q_PROJ>
J 0
(7643 2);
DISPLAY 1.212766 (7643 2);
FORCEPROP 1 LAST CUSTOM_TXT_CDS <Q_REV>
J 0
(9841 3);
DISPLAY 1.212766 (9841 3);
FORCEPROP 1 LAST CUSTOM_TXT_CDS <CON_PAGE_NUM> OF <CON_TOTAL_PAGES>
J 0
(9579 -82);
DISPLAY 0.978723 (9579 -82);
FORCEPROP 1 LAST Q_TITLE VCCIN CPU0 VR PHASE 3&4 (3/7)
J 0
(725 -50);
DISPLAY 2.446809 (725 -50);
PAINT GREEN (725 -50);
FORCEPROP 1 LAST Q_DEPT 
J 1
(6262 -51);
DISPLAY 1.957447 (6262 -51);
PAINT GREEN (6262 -51);
FORCEPROP 2 LAST CDS_XR_PAGE_TITLE CR-268 : @S9S_MB_2U_LIB.S9S_MB_2U(SCH_1):PAGE268
J 0
(2135 5150);
DISPLAY 0.638298 (2135 5150);
PAINT PINK (2135 5150);
DISPLAY INVISIBLE (2135 5150);
FORCEPROP 1 LAST COMMENT_BODY TRUE
J 0
(10037 -113);
DISPLAY 0.978723 (10037 -113);
PAINT GREEN (10037 -113);
DISPLAY INVISIBLE (10037 -113);
FORCEPROP 2 LAST PAGE_BORDER TRUE
J 0
(2135 5150);
DISPLAY 0.638298 (2135 5150);
PAINT PINK (2135 5150);
DISPLAY INVISIBLE (2135 5150);
FORCEPROP 1 LAST CDS_LMAN_SYM_OUTLINE -9475,6775,100,-125
J 0
(10025 -100);
DISPLAY 0.468085 (10025 -100);
PAINT GREEN (10025 -100);
DISPLAY INVISIBLE (10025 -100);
FORCEPROP 2 LAST CDS_LIB pure_quanta
J 0
(10025 -100);
DISPLAY INVISIBLE (10025 -100);
WIRE 16 -1 (3000 2725)(3000 2775);
WIRE 16 -1 (3425 2725)(3000 2725);
WIRE 16 -1 (3000 2600)(3000 2725);
WIRE 16 -1 (3025 5550)(3025 5600);
WIRE 16 -1 (3450 5550)(3025 5550);
WIRE 16 -1 (3025 5425)(3025 5550);
WIRE 16 -1 (7125 2725)(7125 2650);
WIRE 16 -1 (7150 5550)(7150 5475);
WIRE 16 -1 (9500 1650)(9500 1500);
WIRE 16 -1 (9475 4475)(9475 4325);
WIRE 16 -1 (2600 900)(2600 825);
WIRE 16 -1 (2500 1300)(2500 1275);
WIRE 16 -1 (2500 1300)(3225 1300);
WIRE 16 -1 (2625 3725)(2625 3650);
WIRE 16 -1 (3000 1900)(3000 1800);
WIRE 16 -1 (3425 2400)(3425 2325);
WIRE 16 -1 (2525 4125)(2525 4100);
WIRE 16 -1 (2525 4125)(3250 4125);
WIRE 16 -1 (3025 4725)(3025 4625);
WIRE 16 -1 (3450 5225)(3450 5150);
WIRE 16 -1 (5175 900)(5175 825);
WIRE 16 -1 (5175 950)(5175 900);
WIRE 16 -1 (4925 900)(5175 900);
WIRE 16 -1 (5200 3725)(5200 3650);
WIRE 16 -1 (5200 3775)(5200 3725);
WIRE 16 -1 (4950 3725)(5200 3725);
WIRE 16 -1 (7125 2025)(7125 2150);
WIRE 16 -1 (7150 4850)(7150 4975);
WIRE 16 -1 (9500 975)(9500 1075);
WIRE 16 -1 (9475 3800)(9475 3900);
WIRE 16 -1 (2625 4025)(2625 3925);
WIRE 16 -1 (2625 4025)(4100 4025);
FORCEPROP 2 LAST SIG_NAME PVCCIN_CPU0_LSET3
J 0
(3265 4035);
DISPLAY 0.617021 (3265 4035);
WIRE 16 -1 (7200 3775)(8575 3775);
WIRE 16 -1 (8575 4325)(7400 4325);
WIRE 16 -1 (8575 3775)(8575 4325);
WIRE 16 -1 (8750 4325)(8575 4325);
WIRE 16 -1 (8750 4325)(8750 4225);
WIRE 16 -1 (8750 4325)(9175 4325);
WIRE 16 -1 (9175 4225)(9175 4325);
WIRE 16 -1 (9475 4325)(9175 4325);
WIRE 16 -1 (8750 3900)(8750 4025);
WIRE 16 -1 (9175 3900)(8750 3900);
WIRE 16 -1 (9175 4025)(9175 3900);
WIRE 16 -1 (9475 3900)(9175 3900);
WIRE 16 -1 (8775 1075)(8775 1200);
WIRE 16 -1 (9200 1075)(8775 1075);
WIRE 16 -1 (9200 1075)(9200 1200);
WIRE 16 -1 (9500 1075)(9200 1075);
WIRE 16 -1 (8525 975)(7175 975);
WIRE 16 -1 (7350 1500)(8525 1500);
WIRE 16 -1 (8525 975)(8525 1500);
WIRE 16 -1 (8525 1500)(8775 1500);
WIRE 16 -1 (8775 1500)(8775 1400);
WIRE 16 -1 (8775 1500)(9200 1500);
WIRE 16 -1 (9200 1500)(9200 1400);
WIRE 16 -1 (9200 1500)(9500 1500);
WIRE 16 -1 (7400 4075)(7925 4075);
FORCEPROP 2 LAST SIG_NAME IND_P0_CPL4
J 0
(7515 4085);
DISPLAY 0.617021 (7515 4085);
WIRE 16 -1 (4950 4925)(5125 4925);
WIRE 16 -1 (4950 4975)(5125 4975);
WIRE 16 -1 (5125 4925)(5125 4975);
WIRE 16 -1 (5125 5475)(5125 4975);
WIRE 16 -1 (5125 5475)(5350 5475);
WIRE 16 -1 (5350 5325)(5350 5475);
WIRE 16 -1 (5350 5475)(5750 5475);
WIRE 16 -1 (5750 5325)(5750 5475);
WIRE 16 -1 (5750 5475)(6150 5475);
WIRE 16 -1 (6150 5475)(6150 5325);
WIRE 16 -1 (6150 5475)(6550 5475);
WIRE 16 -1 (6550 5325)(6550 5475);
WIRE 16 -1 (6550 5475)(6925 5475);
WIRE 16 -1 (6925 5325)(6925 5475);
WIRE 16 -1 (7150 5475)(6925 5475);
WIRE 16 -1 (5350 5125)(5350 4975);
WIRE 16 -1 (5350 4975)(5750 4975);
WIRE 16 -1 (5750 5125)(5750 4975);
WIRE 16 -1 (6150 4975)(5750 4975);
WIRE 16 -1 (6150 5125)(6150 4975);
WIRE 16 -1 (6150 4975)(6550 4975);
WIRE 16 -1 (6550 5125)(6550 4975);
WIRE 16 -1 (6550 4975)(6925 4975);
WIRE 16 -1 (6925 5125)(6925 4975);
WIRE 16 -1 (7150 4975)(6925 4975);
WIRE 16 -1 (5800 4075)(6600 4075);
FORCEPROP 2 LAST SIG_NAME IND_P0_CPL3
J 0
(5965 4085);
DISPLAY 0.617021 (5965 4085);
WIRE 16 -1 (5900 4775)(6525 4775);
FORCEPROP 2 LAST SIG_NAME SW_PVCCIN_CPU0_BOOT3_R
J 0
(6165 4785);
DISPLAY 0.617021 (6165 4785);
WIRE 16 -1 (6525 4775)(6525 4700);
WIRE 16 -1 (4950 4425)(6525 4425);
FORCEPROP 2 LAST SIG_NAME SW_PVCCIN_CPU0_BOOTR3
J 0
(5140 4435);
DISPLAY 0.617021 (5140 4435);
WIRE 16 -1 (6525 4425)(6525 4500);
WIRE 16 -1 (4950 4325)(6600 4325);
FORCEPROP 2 LAST SIG_NAME SW_PVCCIN_CPU0_SW3
J 0
(5140 4335);
DISPLAY 0.617021 (5140 4335);
WIRE 16 -1 (4950 4675)(5100 4675);
WIRE 16 -1 (5100 4675)(5100 4775);
FORCEPROP 2 LAST SIG_NAME SW_PVCCIN_CPU0_BOOT3
J 0
(4940 4785);
DISPLAY 0.617021 (4940 4785);
WIRE 16 -1 (5100 4775)(5700 4775);
WIRE 16 -1 (5250 3775)(7000 3775);
FORCEPROP 2 LAST SIG_NAME PVCCIN_CPU0_VOS3
J 0
(5390 3785);
DISPLAY 0.617021 (5390 3785);
WIRE 16 -1 (5250 4075)(5250 3775);
WIRE 16 -1 (4950 4075)(5250 4075);
WIRE 16 -1 (4925 2100)(5100 2100);
WIRE 16 -1 (5100 2100)(5100 2150);
WIRE 16 -1 (4925 2150)(5100 2150);
WIRE 16 -1 (5100 2650)(5100 2150);
WIRE 16 -1 (5100 2650)(5325 2650);
WIRE 16 -1 (5325 2500)(5325 2650);
WIRE 16 -1 (5325 2650)(5725 2650);
WIRE 16 -1 (5725 2500)(5725 2650);
WIRE 16 -1 (6125 2650)(6125 2500);
WIRE 16 -1 (5725 2650)(6125 2650);
WIRE 16 -1 (6125 2650)(6525 2650);
WIRE 16 -1 (6525 2500)(6525 2650);
WIRE 16 -1 (6525 2650)(6900 2650);
WIRE 16 -1 (6900 2500)(6900 2650);
WIRE 16 -1 (7125 2650)(6900 2650);
WIRE 16 -1 (5325 2300)(5325 2150);
WIRE 16 -1 (5325 2150)(5725 2150);
WIRE 16 -1 (5725 2300)(5725 2150);
WIRE 16 -1 (6125 2150)(5725 2150);
WIRE 16 -1 (6125 2300)(6125 2150);
WIRE 16 -1 (6125 2150)(6525 2150);
WIRE 16 -1 (6525 2300)(6525 2150);
WIRE 16 -1 (6525 2150)(6900 2150);
WIRE 16 -1 (6900 2300)(6900 2150);
WIRE 16 -1 (7125 2150)(6900 2150);
WIRE 16 -1 (7350 1250)(7850 1250);
FORCEPROP 2 LAST SIG_NAME IND_P0_CPL5
J 0
(7465 1260);
DISPLAY 0.617021 (7465 1260);
WIRE 16 -1 (4950 3775)(5200 3775);
WIRE 16 -1 (4950 3825)(5200 3825);
WIRE 16 -1 (5200 3825)(5200 3775);
WIRE 16 -1 (5200 3875)(5200 3825);
WIRE 16 -1 (4950 3875)(5200 3875);
WIRE 16 -1 (4925 1850)(5075 1850);
WIRE 16 -1 (5075 1850)(5075 1950);
FORCEPROP 2 LAST SIG_NAME SW_PVCCIN_CPU0_BOOT4
J 0
(4890 1960);
DISPLAY 0.617021 (4890 1960);
WIRE 16 -1 (5075 1950)(5675 1950);
WIRE 16 -1 (6500 1950)(6500 1875);
WIRE 16 -1 (5875 1950)(6500 1950);
FORCEPROP 2 LAST SIG_NAME SW_PVCCIN_CPU0_BOOT4_R
J 0
(6165 1960);
DISPLAY 0.617021 (6165 1960);
WIRE 16 -1 (5900 1250)(6550 1250);
FORCEPROP 2 LAST SIG_NAME IND_P0_CPL4
J 0
(6065 1260);
DISPLAY 0.617021 (6065 1260);
WIRE 16 -1 (4925 1600)(6500 1600);
FORCEPROP 2 LAST SIG_NAME SW_PVCCIN_CPU0_BOOTR4
J 0
(5115 1610);
DISPLAY 0.617021 (5115 1610);
WIRE 16 -1 (6500 1600)(6500 1675);
WIRE 16 -1 (4925 1500)(6550 1500);
FORCEPROP 2 LAST SIG_NAME SW_PVCCIN_CPU0_SW4
J 0
(5115 1510);
DISPLAY 0.617021 (5115 1510);
WIRE 16 -1 (4925 1250)(5275 1250);
WIRE 16 -1 (5275 1250)(5275 975);
WIRE 16 -1 (5275 975)(6975 975);
FORCEPROP 2 LAST SIG_NAME PVCCIN_CPU0_VOS4
J 0
(5465 985);
DISPLAY 0.617021 (5465 985);
WIRE 16 -1 (4925 950)(5175 950);
WIRE 16 -1 (4925 1000)(5175 1000);
WIRE 16 -1 (5175 1000)(5175 950);
WIRE 16 -1 (5175 1050)(5175 1000);
WIRE 16 -1 (4925 1050)(5175 1050);
WIRE 16 -1 (3450 5550)(3450 5425);
WIRE 16 -1 (4025 5550)(3450 5550);
WIRE 16 -1 (4025 4975)(4025 5550);
WIRE 16 -1 (4100 4975)(4025 4975);
WIRE 16 -1 (3025 5075)(3025 4925);
WIRE 16 -1 (3025 5225)(3025 5075);
WIRE 16 -1 (3025 5075)(3425 5075);
WIRE 16 -1 (3425 4675)(3425 5075);
WIRE 16 -1 (3425 4675)(4000 4675);
FORCEPROP 2 LAST SIG_NAME PVCCIN_CPU0_VDD3
J 0
(3465 4685);
DISPLAY 0.617021 (3465 4685);
WIRE 16 -1 (4000 4675)(4100 4675);
WIRE 16 -1 (4000 4475)(4000 4675);
WIRE 16 -1 (4100 4475)(4000 4475);
WIRE 16 -1 (4000 4125)(3450 4125);
WIRE 16 -1 (3150 4225)(4000 4225);
FORCEPROP 2 LAST SIG_NAME PVCCIN_CPU0_VREF
J 0
(3265 4235);
DISPLAY 0.617021 (3265 4235);
WIRE 16 -1 (4000 4225)(4000 4125);
FORCEPROP 0 LAST CDS_PHYS_NET_NAME PVCCIN_CPU0_VREF
J 0
(4000 4150);
PAINT MONO (4000 4150);
DISPLAY INVISIBLE (4000 4150);
WIRE 16 -1 (4000 4225)(4100 4225);
WIRE 16 -1 (4100 4325)(3150 4325);
FORCEPROP 2 LAST SIG_NAME PVCCIN_CPU0_IMON3
J 0
(3265 4335);
DISPLAY 0.617021 (3265 4335);
WIRE 16 -1 (3425 2725)(3425 2600);
WIRE 16 -1 (4000 2725)(3425 2725);
WIRE 16 -1 (4000 2150)(4000 2725);
WIRE 16 -1 (4075 2150)(4000 2150);
WIRE 16 -1 (4100 3825)(3150 3825);
FORCEPROP 2 LAST SIG_NAME PVCCIN_CPU0_ATSEN
J 0
(3265 3835);
DISPLAY 0.617021 (3265 3835);
WIRE 16 -1 (4100 3725)(3150 3725);
FORCEPROP 2 LAST SIG_NAME PVCCIN_CPU0_PWM3
J 0
(3265 3735);
DISPLAY 0.617021 (3265 3735);
WIRE 16 -1 (4075 1650)(3975 1650);
WIRE 16 -1 (3975 1650)(3975 1850);
WIRE 16 -1 (4075 1850)(3975 1850);
WIRE 16 -1 (3975 1850)(3400 1850);
FORCEPROP 2 LAST SIG_NAME PVCCIN_CPU0_VDD4
J 0
(3440 1860);
DISPLAY 0.617021 (3440 1860);
WIRE 16 -1 (3400 1850)(3400 2250);
WIRE 16 -1 (3000 2250)(3000 2100);
WIRE 16 -1 (3000 2400)(3000 2250);
WIRE 16 -1 (3000 2250)(3400 2250);
WIRE 16 -1 (4075 1500)(3125 1500);
FORCEPROP 2 LAST SIG_NAME PVCCIN_CPU0_IMON4
J 0
(3240 1510);
DISPLAY 0.617021 (3240 1510);
WIRE 16 -1 (4075 900)(3125 900);
FORCEPROP 2 LAST SIG_NAME PVCCIN_CPU0_PWM4
J 0
(3240 910);
DISPLAY 0.617021 (3240 910);
WIRE 16 -1 (4075 1000)(3125 1000);
FORCEPROP 2 LAST SIG_NAME PVCCIN_CPU0_ATSEN
J 0
(3240 1010);
DISPLAY 0.617021 (3240 1010);
WIRE 16 -1 (3975 1300)(3425 1300);
WIRE 16 -1 (3125 1400)(3975 1400);
FORCEPROP 2 LAST SIG_NAME PVCCIN_CPU0_VREF
J 0
(3240 1410);
DISPLAY 0.617021 (3240 1410);
WIRE 16 -1 (3975 1400)(4075 1400);
WIRE 16 -1 (3975 1400)(3975 1300);
FORCEPROP 0 LAST CDS_PHYS_NET_NAME PVCCIN_CPU0_VREF
J 0
(3975 1325);
PAINT MONO (3975 1325);
DISPLAY INVISIBLE (3975 1325);
WIRE 16 -1 (2600 1200)(2600 1100);
WIRE 16 -1 (2600 1200)(4075 1200);
FORCEPROP 2 LAST SIG_NAME PVCCIN_CPU0_LSET4
J 0
(3240 1210);
DISPLAY 0.617021 (3240 1210);
DOT 1 (3975 1400);
DOT 1 (3975 1850);
DOT 1 (3000 2250);
DOT 1 (3000 2725);
DOT 1 (3425 2725);
DOT 1 (3025 5075);
DOT 1 (3025 5550);
DOT 1 (3450 5550);
DOT 1 (4000 4225);
DOT 1 (4000 4675);
DOT 1 (5175 900);
DOT 1 (5175 1000);
DOT 1 (5175 950);
DOT 1 (5100 2150);
DOT 1 (5325 2650);
DOT 1 (5200 3725);
DOT 1 (5200 3775);
DOT 1 (5200 3825);
DOT 1 (5725 2150);
DOT 1 (6125 2150);
DOT 1 (5725 2650);
DOT 1 (6125 2650);
DOT 1 (6525 2150);
DOT 1 (6525 2650);
DOT 1 (8525 1500);
DOT 1 (6900 2150);
DOT 1 (6900 2650);
DOT 1 (5125 4975);
DOT 1 (5350 5475);
DOT 1 (5750 4975);
DOT 1 (6150 4975);
DOT 1 (6550 4975);
DOT 1 (5750 5475);
DOT 1 (6150 5475);
DOT 1 (6550 5475);
DOT 1 (6925 4975);
DOT 1 (6925 5475);
DOT 1 (8750 4325);
DOT 1 (8575 4325);
DOT 1 (8775 1500);
DOT 1 (9200 1075);
DOT 1 (9200 1500);
DOT 1 (9175 3900);
DOT 1 (9175 4325);
FORCENOTE
PVCCIN_CPU0_PHASE4
(4150 2675) 0;
DISPLAY LEFT (4150 2675);
DISPLAY 1.021277 (4150 2675);
PAINT WHITE (4150 2675);
FORCENOTE
PVCCIN_CPU0_PHASE3
(4175 5500) 0;
DISPLAY LEFT (4175 5500);
DISPLAY 1.021277 (4175 5500);
PAINT WHITE (4175 5500);
FORCENOTE
DCR=2-3,0.27M OHM
(7350 1625) 0;
DISPLAY LEFT (7350 1625);
DISPLAY 1.021277 (7350 1625);
FORCENOTE
DCR=1-4,0.105M OHM
(7350 1700) 0;
DISPLAY LEFT (7350 1700);
DISPLAY 1.021277 (7350 1700);
FORCENOTE
ISAT=70A@100C
(7350 1775) 0;
DISPLAY LEFT (7350 1775);
DISPLAY 1.021277 (7350 1775);
FORCENOTE
11.0*7.5*12.5
(7350 1850) 0;
DISPLAY LEFT (7350 1850);
DISPLAY 1.021277 (7350 1850);
FORCENOTE
PGL6303.151HLT 
(7350 1925) 0;
DISPLAY LEFT (7350 1925);
DISPLAY 1.021277 (7350 1925);
FORCENOTE
DCR=2-3,0.27M OHM
(7375 4500) 0;
DISPLAY LEFT (7375 4500);
DISPLAY 1.021277 (7375 4500);
FORCENOTE
DCR=1-4,0.105M OHM
(7375 4575) 0;
DISPLAY LEFT (7375 4575);
DISPLAY 1.021277 (7375 4575);
FORCENOTE
PGL6303.151HLT 
(7375 4800) 0;
DISPLAY LEFT (7375 4800);
DISPLAY 1.021277 (7375 4800);
FORCENOTE
11.0*7.5*12.5
(7375 4725) 0;
DISPLAY LEFT (7375 4725);
DISPLAY 1.021277 (7375 4725);
FORCENOTE
ISAT=70A@100C
(7375 4650) 0;
DISPLAY LEFT (7375 4650);
DISPLAY 1.021277 (7375 4650);
QUIT
